(lib_symbols
	(symbol "antmicroCapacitors0402:C_100n_0402"
			(pin_numbers hide)
			(pin_names hide)
			(exclude_from_sim no)
			(in_bom yes)
			(on_board yes)
			(property "Reference" "C"
				(at 20.32 -5.08 0)
				(effects
					(font
						(size 1.27 1.27)
						(thickness 0.15)
					)
					(justify left bottom)
				)
			)
			(property "Value" "C_100n_0402"
				(at 20.32 -10.16 0)
				(effects
					(font
						(size 1.27 1.27)
						(thickness 0.15)
					)
					(justify left bottom)
					(hide yes)
				)
			)
			(property "Footprint" "antmicro-footprints:C_0402_1005Metric"
				(at 20.32 -12.7 0)
				(effects
					(font
						(size 1.27 1.27)
						(thickness 0.15)
					)
					(justify left bottom)
					(hide yes)
				)
			)
			(property "Datasheet" "https://www.murata.com/products/productdetail?partno=GRM155R61H104KE14%23"
				(at 20.32 -15.24 0)
				(effects
					(font
						(size 1.27 1.27)
						(thickness 0.15)
					)
					(justify left bottom)
					(hide yes)
				)
			)
			(property "Description" "SMD Multilayer Ceramic Capacitor, 0.1 µF, 50 V, 0402 [1005 Metric], ± 10%, X5R, GRM Series"
				(at 0 0 0)
				(effects
					(font
						(size 1.27 1.27)
					)
					(hide yes)
				)
			)
			(property "MPN" "GRM155R61H104KE14D"
				(at 20.32 -17.78 0)
				(effects
					(font
						(size 1.27 1.27)
						(thickness 0.15)
					)
					(justify left bottom)
					(hide yes)
				)
			)
			(property "Manufacturer" "Murata"
				(at 20.32 -20.32 0)
				(effects
					(font
						(size 1.27 1.27)
						(thickness 0.15)
					)
					(justify left bottom)
					(hide yes)
				)
			)
			(property "License" "Apache-2.0"
				(at 20.32 -22.86 0)
				(effects
					(font
						(size 1.27 1.27)
						(thickness 0.15)
					)
					(justify left bottom)
					(hide yes)
				)
			)
			(property "Author" "Antmicro"
				(at 20.32 -25.4 0)
				(effects
					(font
						(size 1.27 1.27)
						(thickness 0.15)
					)
					(justify left bottom)
					(hide yes)
				)
			)
			(property "Val" "100n"
				(at 20.32 -7.62 0)
				(effects
					(font
						(size 1.27 1.27)
						(thickness 0.15)
					)
					(justify left bottom)
				)
			)
			(property "Voltage" "50V"
				(at 20.32 -27.94 0)
				(effects
					(font
						(size 1.27 1.27)
					)
					(justify left bottom)
					(hide yes)
				)
			)
			(property "Dielectric" "X5R"
				(at 20.32 -30.48 0)
				(effects
					(font
						(size 1.27 1.27)
					)
					(justify left bottom)
					(hide yes)
				)
			)
			(property "ki_keywords" "0402, SMT, CAPACITOR, PASSIVE, CERAMIC, MLCC"
				(at 0 0 0)
				(effects
					(font
						(size 1.27 1.27)
					)
					(hide yes)
				)
			)
			(symbol "C_100n_0402_0_1"
				(polyline
					(pts
						(xy 2.032 -1.524) (xy 2.032 1.524)
					)
					(stroke
						(width 0.3048)
						(type default)
					)
					(fill
						(type none)
					)
				)
				(polyline
					(pts
						(xy 3.048 -1.524) (xy 3.048 1.524)
					)
					(stroke
						(width 0.3302)
						(type default)
					)
					(fill
						(type none)
					)
				)
			)
			(symbol "C_100n_0402_1_1"
				(pin passive line
					(at 0 0 0)
					(length 2.032)
					(name "~"
						(effects
							(font
								(size 1.27 1.27)
							)
						)
					)
					(number "1"
						(effects
							(font
								(size 1.27 1.27)
							)
						)
					)
				)
				(pin passive line
					(at 5.08 0 180)
					(length 2.032)
					(name "~"
						(effects
							(font
								(size 1.27 1.27)
							)
						)
					)
					(number "2"
						(effects
							(font
								(size 1.27 1.27)
							)
						)
					)
				)
			)
		)
	(symbol "antmicroCapacitors0402:C_10p_0402"
			(pin_numbers hide)
			(pin_names hide)
			(exclude_from_sim no)
			(in_bom yes)
			(on_board yes)
			(property "Reference" "C"
				(at 20.32 -5.08 0)
				(effects
					(font
						(size 1.27 1.27)
						(thickness 0.15)
					)
					(justify left bottom)
				)
			)
			(property "Value" "C_10p_0402"
				(at 20.32 -10.16 0)
				(effects
					(font
						(size 1.27 1.27)
						(thickness 0.15)
					)
					(justify left bottom)
					(hide yes)
				)
			)
			(property "Footprint" "antmicro-footprints:C_0402_1005Metric"
				(at 20.32 -12.7 0)
				(effects
					(font
						(size 1.27 1.27)
						(thickness 0.15)
					)
					(justify left bottom)
					(hide yes)
				)
			)
			(property "Datasheet" "https://www.murata.com/products/productdetail?partno=GCM1555C1H100GA16%23"
				(at 20.32 -15.24 0)
				(effects
					(font
						(size 1.27 1.27)
						(thickness 0.15)
					)
					(justify left bottom)
					(hide yes)
				)
			)
			(property "Description" "SMD Multilayer Ceramic Capacitor, 10 pF, 50 V, 0402 [1005 Metric], ± 2%, C0G / NP0, GCM"
				(at 0 0 0)
				(effects
					(font
						(size 1.27 1.27)
					)
					(hide yes)
				)
			)
			(property "MPN" "GCM1555C1H100GA16D"
				(at 20.32 -17.78 0)
				(effects
					(font
						(size 1.27 1.27)
						(thickness 0.15)
					)
					(justify left bottom)
					(hide yes)
				)
			)
			(property "Manufacturer" "Murata"
				(at 20.32 -20.32 0)
				(effects
					(font
						(size 1.27 1.27)
						(thickness 0.15)
					)
					(justify left bottom)
					(hide yes)
				)
			)
			(property "License" "Apache-2.0"
				(at 20.32 -22.86 0)
				(effects
					(font
						(size 1.27 1.27)
						(thickness 0.15)
					)
					(justify left bottom)
					(hide yes)
				)
			)
			(property "Author" "Antmicro"
				(at 20.32 -25.4 0)
				(effects
					(font
						(size 1.27 1.27)
						(thickness 0.15)
					)
					(justify left bottom)
					(hide yes)
				)
			)
			(property "Val" "10p"
				(at 20.32 -7.62 0)
				(effects
					(font
						(size 1.27 1.27)
						(thickness 0.15)
					)
					(justify left bottom)
				)
			)
			(property "Voltage" "50V"
				(at 20.32 -27.94 0)
				(effects
					(font
						(size 1.27 1.27)
					)
					(justify left bottom)
					(hide yes)
				)
			)
			(property "Dielectric" "C0G"
				(at 20.32 -30.48 0)
				(effects
					(font
						(size 1.27 1.27)
					)
					(justify left bottom)
					(hide yes)
				)
			)
			(property "ki_keywords" "0402, SMT, CAPACITOR, PASSIVE"
				(at 0 0 0)
				(effects
					(font
						(size 1.27 1.27)
					)
					(hide yes)
				)
			)
			(symbol "C_10p_0402_0_1"
				(polyline
					(pts
						(xy 2.032 -1.524) (xy 2.032 1.524)
					)
					(stroke
						(width 0.3048)
						(type default)
					)
					(fill
						(type none)
					)
				)
				(polyline
					(pts
						(xy 3.048 -1.524) (xy 3.048 1.524)
					)
					(stroke
						(width 0.3302)
						(type default)
					)
					(fill
						(type none)
					)
				)
			)
			(symbol "C_10p_0402_1_1"
				(pin passive line
					(at 0 0 0)
					(length 2.032)
					(name "~"
						(effects
							(font
								(size 1.27 1.27)
							)
						)
					)
					(number "1"
						(effects
							(font
								(size 1.27 1.27)
							)
						)
					)
				)
				(pin passive line
					(at 5.08 0 180)
					(length 2.032)
					(name "~"
						(effects
							(font
								(size 1.27 1.27)
							)
						)
					)
					(number "2"
						(effects
							(font
								(size 1.27 1.27)
							)
						)
					)
				)
			)
		)
	(symbol "antmicroCapacitors0402:C_10u_0402"
			(pin_numbers hide)
			(pin_names hide)
			(exclude_from_sim no)
			(in_bom yes)
			(on_board yes)
			(property "Reference" "C"
				(at 20.32 -5.08 0)
				(effects
					(font
						(size 1.27 1.27)
						(thickness 0.15)
					)
					(justify left bottom)
				)
			)
			(property "Value" "C_10u_0402"
				(at 20.32 -10.16 0)
				(effects
					(font
						(size 1.27 1.27)
						(thickness 0.15)
					)
					(justify left bottom)
					(hide yes)
				)
			)
			(property "Footprint" "antmicro-footprints:C_0402_1005Metric"
				(at 20.32 -12.7 0)
				(effects
					(font
						(size 1.27 1.27)
						(thickness 0.15)
					)
					(justify left bottom)
					(hide yes)
				)
			)
			(property "Datasheet" "https://www.yageo.com/en/Chart/Download/pdf/CC0402MRX5R5BB106"
				(at 20.32 -15.24 0)
				(effects
					(font
						(size 1.27 1.27)
						(thickness 0.15)
					)
					(justify left bottom)
					(hide yes)
				)
			)
			(property "Description" "SMD Multilayer Ceramic Capacitor, 10 µF, 6.3 V, 0402 [1005 Metric], ± 20%, X5R, CC Series"
				(at 0 0 0)
				(effects
					(font
						(size 1.27 1.27)
					)
					(hide yes)
				)
			)
			(property "MPN" "CC0402MRX5R5BB106"
				(at 20.32 -17.78 0)
				(effects
					(font
						(size 1.27 1.27)
						(thickness 0.15)
					)
					(justify left bottom)
					(hide yes)
				)
			)
			(property "Manufacturer" "YAGEO"
				(at 20.32 -20.32 0)
				(effects
					(font
						(size 1.27 1.27)
						(thickness 0.15)
					)
					(justify left bottom)
					(hide yes)
				)
			)
			(property "License" "Apache-2.0"
				(at 20.32 -22.86 0)
				(effects
					(font
						(size 1.27 1.27)
						(thickness 0.15)
					)
					(justify left bottom)
					(hide yes)
				)
			)
			(property "Author" "Antmicro"
				(at 20.32 -25.4 0)
				(effects
					(font
						(size 1.27 1.27)
						(thickness 0.15)
					)
					(justify left bottom)
					(hide yes)
				)
			)
			(property "Val" "10u"
				(at 20.32 -7.62 0)
				(effects
					(font
						(size 1.27 1.27)
						(thickness 0.15)
					)
					(justify left bottom)
				)
			)
			(property "Voltage" ""
				(at 20.32 -27.94 0)
				(effects
					(font
						(size 1.27 1.27)
					)
					(justify left bottom)
					(hide yes)
				)
			)
			(property "Dielectric" ""
				(at 20.32 -30.48 0)
				(effects
					(font
						(size 1.27 1.27)
					)
					(justify left bottom)
					(hide yes)
				)
			)
			(property "ki_keywords" "0402, SMT, CAPACITOR, PASSIVE, MLCC, CERAMIC"
				(at 0 0 0)
				(effects
					(font
						(size 1.27 1.27)
					)
					(hide yes)
				)
			)
			(symbol "C_10u_0402_0_1"
				(polyline
					(pts
						(xy 2.032 -1.524) (xy 2.032 1.524)
					)
					(stroke
						(width 0.3048)
						(type default)
					)
					(fill
						(type none)
					)
				)
				(polyline
					(pts
						(xy 3.048 -1.524) (xy 3.048 1.524)
					)
					(stroke
						(width 0.3302)
						(type default)
					)
					(fill
						(type none)
					)
				)
			)
			(symbol "C_10u_0402_1_1"
				(pin passive line
					(at 0 0 0)
					(length 2.032)
					(name "~"
						(effects
							(font
								(size 1.27 1.27)
							)
						)
					)
					(number "1"
						(effects
							(font
								(size 1.27 1.27)
							)
						)
					)
				)
				(pin passive line
					(at 5.08 0 180)
					(length 2.032)
					(name "~"
						(effects
							(font
								(size 1.27 1.27)
							)
						)
					)
					(number "2"
						(effects
							(font
								(size 1.27 1.27)
							)
						)
					)
				)
			)
		)
	(symbol "antmicroCapacitors0402:C_1u_0402"
			(pin_numbers hide)
			(pin_names hide)
			(exclude_from_sim no)
			(in_bom yes)
			(on_board yes)
			(property "Reference" "C"
				(at 20.32 -5.08 0)
				(effects
					(font
						(size 1.27 1.27)
						(thickness 0.15)
					)
					(justify left bottom)
				)
			)
			(property "Value" "C_1u_0402"
				(at 20.32 -10.16 0)
				(effects
					(font
						(size 1.27 1.27)
						(thickness 0.15)
					)
					(justify left bottom)
					(hide yes)
				)
			)
			(property "Footprint" "antmicro-footprints:C_0402_1005Metric"
				(at 20.32 -12.7 0)
				(effects
					(font
						(size 1.27 1.27)
						(thickness 0.15)
					)
					(justify left bottom)
					(hide yes)
				)
			)
			(property "Datasheet" "https://product.tdk.com/en/search/capacitor/ceramic/mlcc/info?part_no=C1005X6S1A105K050BC"
				(at 20.32 -15.24 0)
				(effects
					(font
						(size 1.27 1.27)
						(thickness 0.15)
					)
					(justify left bottom)
					(hide yes)
				)
			)
			(property "Description" "SMD Multilayer Ceramic Capacitor, 1 µF, 10 V, 0402 [1005 Metric], ± 10%, X6S, C"
				(at 0 0 0)
				(effects
					(font
						(size 1.27 1.27)
					)
					(hide yes)
				)
			)
			(property "MPN" "C1005X6S1A105K050BC"
				(at 20.32 -17.78 0)
				(effects
					(font
						(size 1.27 1.27)
						(thickness 0.15)
					)
					(justify left bottom)
					(hide yes)
				)
			)
			(property "Manufacturer" "TDK"
				(at 20.32 -20.32 0)
				(effects
					(font
						(size 1.27 1.27)
						(thickness 0.15)
					)
					(justify left bottom)
					(hide yes)
				)
			)
			(property "License" "Apache-2.0"
				(at 20.32 -22.86 0)
				(effects
					(font
						(size 1.27 1.27)
						(thickness 0.15)
					)
					(justify left bottom)
					(hide yes)
				)
			)
			(property "Author" "Antmicro"
				(at 20.32 -25.4 0)
				(effects
					(font
						(size 1.27 1.27)
						(thickness 0.15)
					)
					(justify left bottom)
					(hide yes)
				)
			)
			(property "Val" "1u"
				(at 20.32 -7.62 0)
				(effects
					(font
						(size 1.27 1.27)
						(thickness 0.15)
					)
					(justify left bottom)
				)
			)
			(property "Voltage" ""
				(at 20.32 -27.94 0)
				(effects
					(font
						(size 1.27 1.27)
					)
					(justify left bottom)
					(hide yes)
				)
			)
			(property "Dielectric" ""
				(at 20.32 -30.48 0)
				(effects
					(font
						(size 1.27 1.27)
					)
					(justify left bottom)
					(hide yes)
				)
			)
			(property "ki_keywords" "0402, SMT, CAPACITOR, PASSIVE, CERAMIC, MLCC"
				(at 0 0 0)
				(effects
					(font
						(size 1.27 1.27)
					)
					(hide yes)
				)
			)
			(symbol "C_1u_0402_0_1"
				(polyline
					(pts
						(xy 2.032 -1.524) (xy 2.032 1.524)
					)
					(stroke
						(width 0.3048)
						(type default)
					)
					(fill
						(type none)
					)
				)
				(polyline
					(pts
						(xy 3.048 -1.524) (xy 3.048 1.524)
					)
					(stroke
						(width 0.3302)
						(type default)
					)
					(fill
						(type none)
					)
				)
			)
			(symbol "C_1u_0402_1_1"
				(pin passive line
					(at 0 0 0)
					(length 2.032)
					(name "~"
						(effects
							(font
								(size 1.27 1.27)
							)
						)
					)
					(number "1"
						(effects
							(font
								(size 1.27 1.27)
							)
						)
					)
				)
				(pin passive line
					(at 5.08 0 180)
					(length 2.032)
					(name "~"
						(effects
							(font
								(size 1.27 1.27)
							)
						)
					)
					(number "2"
						(effects
							(font
								(size 1.27 1.27)
							)
						)
					)
				)
			)
		)
	(symbol "antmicroCapacitors0402:C_220n_0402"
			(pin_numbers hide)
			(pin_names hide)
			(exclude_from_sim no)
			(in_bom yes)
			(on_board yes)
			(property "Reference" "C"
				(at 20.32 -5.08 0)
				(effects
					(font
						(size 1.27 1.27)
						(thickness 0.15)
					)
					(justify left bottom)
				)
			)
			(property "Value" "C_220n_0402"
				(at 20.32 -10.16 0)
				(effects
					(font
						(size 1.27 1.27)
						(thickness 0.15)
					)
					(justify left bottom)
					(hide yes)
				)
			)
			(property "Footprint" "antmicro-footprints:C_0402_1005Metric"
				(at 20.32 -12.7 0)
				(effects
					(font
						(size 1.27 1.27)
						(thickness 0.15)
					)
					(justify left bottom)
					(hide yes)
				)
			)
			(property "Datasheet" "https://www.yageo.com/en/Chart/Download/pdf/CC0402KRX5R6BB224"
				(at 20.32 -15.24 0)
				(effects
					(font
						(size 1.27 1.27)
						(thickness 0.15)
					)
					(justify left bottom)
					(hide yes)
				)
			)
			(property "Description" "SMD Multilayer Ceramic Capacitor, 0.22 µF, 10 V, 0402 [1005 Metric], ± 10%, X5R, CC Series"
				(at 0 0 0)
				(effects
					(font
						(size 1.27 1.27)
					)
					(hide yes)
				)
			)
			(property "MPN" "CC0402KRX5R6BB224"
				(at 20.32 -17.78 0)
				(effects
					(font
						(size 1.27 1.27)
						(thickness 0.15)
					)
					(justify left bottom)
					(hide yes)
				)
			)
			(property "Manufacturer" "YAGEO"
				(at 20.32 -20.32 0)
				(effects
					(font
						(size 1.27 1.27)
						(thickness 0.15)
					)
					(justify left bottom)
					(hide yes)
				)
			)
			(property "License" "Apache-2.0"
				(at 20.32 -22.86 0)
				(effects
					(font
						(size 1.27 1.27)
						(thickness 0.15)
					)
					(justify left bottom)
					(hide yes)
				)
			)
			(property "Author" "Antmicro"
				(at 20.32 -25.4 0)
				(effects
					(font
						(size 1.27 1.27)
						(thickness 0.15)
					)
					(justify left bottom)
					(hide yes)
				)
			)
			(property "Val" "220n"
				(at 20.32 -7.62 0)
				(effects
					(font
						(size 1.27 1.27)
						(thickness 0.15)
					)
					(justify left bottom)
				)
			)
			(property "Voltage" ""
				(at 20.32 -27.94 0)
				(effects
					(font
						(size 1.27 1.27)
					)
					(justify left bottom)
					(hide yes)
				)
			)
			(property "Dielectric" ""
				(at 20.32 -30.48 0)
				(effects
					(font
						(size 1.27 1.27)
					)
					(justify left bottom)
					(hide yes)
				)
			)
			(property "ki_keywords" "0402, SMT, CAPACITOR, PASSIVE, MLCC, CERAMIC"
				(at 0 0 0)
				(effects
					(font
						(size 1.27 1.27)
					)
					(hide yes)
				)
			)
			(symbol "C_220n_0402_0_1"
				(polyline
					(pts
						(xy 2.032 -1.524) (xy 2.032 1.524)
					)
					(stroke
						(width 0.3048)
						(type default)
					)
					(fill
						(type none)
					)
				)
				(polyline
					(pts
						(xy 3.048 -1.524) (xy 3.048 1.524)
					)
					(stroke
						(width 0.3302)
						(type default)
					)
					(fill
						(type none)
					)
				)
			)
			(symbol "C_220n_0402_1_1"
				(pin passive line
					(at 0 0 0)
					(length 2.032)
					(name "~"
						(effects
							(font
								(size 1.27 1.27)
							)
						)
					)
					(number "1"
						(effects
							(font
								(size 1.27 1.27)
							)
						)
					)
				)
				(pin passive line
					(at 5.08 0 180)
					(length 2.032)
					(name "~"
						(effects
							(font
								(size 1.27 1.27)
							)
						)
					)
					(number "2"
						(effects
							(font
								(size 1.27 1.27)
							)
						)
					)
				)
			)
		)
	(symbol "antmicroCapacitors0402:C_220p_0402"
			(pin_numbers hide)
			(pin_names hide)
			(exclude_from_sim no)
			(in_bom yes)
			(on_board yes)
			(property "Reference" "C"
				(at 20.32 -5.08 0)
				(effects
					(font
						(size 1.27 1.27)
						(thickness 0.15)
					)
					(justify left bottom)
				)
			)
			(property "Value" "C_220p_0402"
				(at 20.32 -10.16 0)
				(effects
					(font
						(size 1.27 1.27)
						(thickness 0.15)
					)
					(justify left bottom)
					(hide yes)
				)
			)
			(property "Footprint" "antmicro-footprints:C_0402_1005Metric"
				(at 20.32 -12.7 0)
				(effects
					(font
						(size 1.27 1.27)
						(thickness 0.15)
					)
					(justify left bottom)
					(hide yes)
				)
			)
			(property "Datasheet" "https://spicat.kyocera-avx.com/product/mlcc/chartview/04025C221JAT2A/"
				(at 20.32 -15.24 0)
				(effects
					(font
						(size 1.27 1.27)
						(thickness 0.15)
					)
					(justify left bottom)
					(hide yes)
				)
			)
			(property "Description" "SMD Multilayer Ceramic Capacitor, 220 pF, 50 V, 0402 [1005 Metric], ± 10%, X7R, MC"
				(at 0 0 0)
				(effects
					(font
						(size 1.27 1.27)
					)
					(hide yes)
				)
			)
			(property "MPN" "04025C221JAT2A"
				(at 20.32 -17.78 0)
				(effects
					(font
						(size 1.27 1.27)
						(thickness 0.15)
					)
					(justify left bottom)
					(hide yes)
				)
			)
			(property "Manufacturer" "KYOCERA AVX"
				(at 20.32 -20.32 0)
				(effects
					(font
						(size 1.27 1.27)
						(thickness 0.15)
					)
					(justify left bottom)
					(hide yes)
				)
			)
			(property "License" "Apache-2.0"
				(at 20.32 -22.86 0)
				(effects
					(font
						(size 1.27 1.27)
						(thickness 0.15)
					)
					(justify left bottom)
					(hide yes)
				)
			)
			(property "Author" "Antmicro"
				(at 20.32 -25.4 0)
				(effects
					(font
						(size 1.27 1.27)
						(thickness 0.15)
					)
					(justify left bottom)
					(hide yes)
				)
			)
			(property "Val" "220p"
				(at 20.32 -7.62 0)
				(effects
					(font
						(size 1.27 1.27)
						(thickness 0.15)
					)
					(justify left bottom)
				)
			)
			(property "Voltage" ""
				(at 20.32 -27.94 0)
				(effects
					(font
						(size 1.27 1.27)
					)
					(justify left bottom)
					(hide yes)
				)
			)
			(property "Dielectric" ""
				(at 20.32 -30.48 0)
				(effects
					(font
						(size 1.27 1.27)
					)
					(justify left bottom)
					(hide yes)
				)
			)
			(property "ki_keywords" "0402, SMT, CAPACITOR, PASSIVE"
				(at 0 0 0)
				(effects
					(font
						(size 1.27 1.27)
					)
					(hide yes)
				)
			)
			(symbol "C_220p_0402_0_1"
				(polyline
					(pts
						(xy 2.032 -1.524) (xy 2.032 1.524)
					)
					(stroke
						(width 0.3048)
						(type default)
					)
					(fill
						(type none)
					)
				)
				(polyline
					(pts
						(xy 3.048 -1.524) (xy 3.048 1.524)
					)
					(stroke
						(width 0.3302)
						(type default)
					)
					(fill
						(type none)
					)
				)
			)
			(symbol "C_220p_0402_1_1"
				(pin passive line
					(at 0 0 0)
					(length 2.032)
					(name "~"
						(effects
							(font
								(size 1.27 1.27)
							)
						)
					)
					(number "1"
						(effects
							(font
								(size 1.27 1.27)
							)
						)
					)
				)
				(pin passive line
					(at 5.08 0 180)
					(length 2.032)
					(name "~"
						(effects
							(font
								(size 1.27 1.27)
							)
						)
					)
					(number "2"
						(effects
							(font
								(size 1.27 1.27)
							)
						)
					)
				)
			)
		)
	(symbol "antmicroCapacitors0402:C_22n_0402"
			(pin_numbers hide)
			(pin_names hide)
			(exclude_from_sim no)
			(in_bom yes)
			(on_board yes)
			(property "Reference" "C"
				(at 20.32 -5.08 0)
				(effects
					(font
						(size 1.27 1.27)
						(thickness 0.15)
					)
					(justify left bottom)
				)
			)
			(property "Value" "C_22n_0402"
				(at 20.32 -10.16 0)
				(effects
					(font
						(size 1.27 1.27)
						(thickness 0.15)
					)
					(justify left bottom)
					(hide yes)
				)
			)
			(property "Footprint" "antmicro-footprints:C_0402_1005Metric"
				(at 20.32 -12.7 0)
				(effects
					(font
						(size 1.27 1.27)
						(thickness 0.15)
					)
					(justify left bottom)
					(hide yes)
				)
			)
			(property "Datasheet" "https://www.murata.com/products/productdetail?partno=GCM155R71H223MA55%23"
				(at 20.32 -15.24 0)
				(effects
					(font
						(size 1.27 1.27)
						(thickness 0.15)
					)
					(justify left bottom)
					(hide yes)
				)
			)
			(property "Description" "SMD Multilayer Ceramic Capacitors, 0.022 µF, 50 V, 20%, 0402 [1005 Metric], X7R"
				(at 0 0 0)
				(effects
					(font
						(size 1.27 1.27)
					)
					(hide yes)
				)
			)
			(property "MPN" "GCM155R71H223MA55D"
				(at 20.32 -17.78 0)
				(effects
					(font
						(size 1.27 1.27)
						(thickness 0.15)
					)
					(justify left bottom)
					(hide yes)
				)
			)
			(property "Manufacturer" "Murata"
				(at 20.32 -20.32 0)
				(effects
					(font
						(size 1.27 1.27)
						(thickness 0.15)
					)
					(justify left bottom)
					(hide yes)
				)
			)
			(property "License" "Apache-2.0"
				(at 20.32 -22.86 0)
				(effects
					(font
						(size 1.27 1.27)
						(thickness 0.15)
					)
					(justify left bottom)
					(hide yes)
				)
			)
			(property "Author" "Antmicro"
				(at 20.32 -25.4 0)
				(effects
					(font
						(size 1.27 1.27)
						(thickness 0.15)
					)
					(justify left bottom)
					(hide yes)
				)
			)
			(property "Val" "22n"
				(at 20.32 -7.62 0)
				(effects
					(font
						(size 1.27 1.27)
						(thickness 0.15)
					)
					(justify left bottom)
				)
			)
			(property "Voltage" ""
				(at 20.32 -27.94 0)
				(effects
					(font
						(size 1.27 1.27)
					)
					(justify left bottom)
					(hide yes)
				)
			)
			(property "Dielectric" ""
				(at 20.32 -30.48 0)
				(effects
					(font
						(size 1.27 1.27)
					)
					(justify left bottom)
					(hide yes)
				)
			)
			(property "ki_keywords" "0402, SMT, CAPACITOR, PASSIVE, CERAMIC, MLCC"
				(at 0 0 0)
				(effects
					(font
						(size 1.27 1.27)
					)
					(hide yes)
				)
			)
			(symbol "C_22n_0402_0_1"
				(polyline
					(pts
						(xy 2.032 -1.524) (xy 2.032 1.524)
					)
					(stroke
						(width 0.3048)
						(type default)
					)
					(fill
						(type none)
					)
				)
				(polyline
					(pts
						(xy 3.048 -1.524) (xy 3.048 1.524)
					)
					(stroke
						(width 0.3302)
						(type default)
					)
					(fill
						(type none)
					)
				)
			)
			(symbol "C_22n_0402_1_1"
				(pin passive line
					(at 0 0 0)
					(length 2.032)
					(name "~"
						(effects
							(font
								(size 1.27 1.27)
							)
						)
					)
					(number "1"
						(effects
							(font
								(size 1.27 1.27)
							)
						)
					)
				)
				(pin passive line
					(at 5.08 0 180)
					(length 2.032)
					(name "~"
						(effects
							(font
								(size 1.27 1.27)
							)
						)
					)
					(number "2"
						(effects
							(font
								(size 1.27 1.27)
							)
						)
					)
				)
			)
		)
	(symbol "antmicroCapacitors0402:C_2u2_0402"
			(pin_numbers hide)
			(pin_names hide)
			(exclude_from_sim no)
			(in_bom yes)
			(on_board yes)
			(property "Reference" "C"
				(at 20.32 -5.08 0)
				(effects
					(font
						(size 1.27 1.27)
						(thickness 0.15)
					)
					(justify left bottom)
				)
			)
			(property "Value" "C_2u2_0402"
				(at 20.32 -10.16 0)
				(effects
					(font
						(size 1.27 1.27)
						(thickness 0.15)
					)
					(justify left bottom)
					(hide yes)
				)
			)
			(property "Footprint" "antmicro-footprints:C_0402_1005Metric"
				(at 20.32 -12.7 0)
				(effects
					(font
						(size 1.27 1.27)
						(thickness 0.15)
					)
					(justify left bottom)
					(hide yes)
				)
			)
			(property "Datasheet" "https://product.tdk.com/en/search/capacitor/ceramic/mlcc/info?part_no=C1005X5R1A225K050BC"
				(at 20.32 -15.24 0)
				(effects
					(font
						(size 1.27 1.27)
						(thickness 0.15)
					)
					(justify left bottom)
					(hide yes)
				)
			)
			(property "Description" "SMD Multilayer Ceramic Capacitor, 2.2 µF, 10 V, 0402 [1005 Metric], ± 10%, X5R, C"
				(at 0 0 0)
				(effects
					(font
						(size 1.27 1.27)
					)
					(hide yes)
				)
			)
			(property "MPN" "C1005X5R1A225K050BC"
				(at 20.32 -17.78 0)
				(effects
					(font
						(size 1.27 1.27)
						(thickness 0.15)
					)
					(justify left bottom)
					(hide yes)
				)
			)
			(property "Manufacturer" "TDK"
				(at 20.32 -20.32 0)
				(effects
					(font
						(size 1.27 1.27)
						(thickness 0.15)
					)
					(justify left bottom)
					(hide yes)
				)
			)
			(property "License" "Apache-2.0"
				(at 20.32 -22.86 0)
				(effects
					(font
						(size 1.27 1.27)
						(thickness 0.15)
					)
					(justify left bottom)
					(hide yes)
				)
			)
			(property "Author" "Antmicro"
				(at 20.32 -25.4 0)
				(effects
					(font
						(size 1.27 1.27)
						(thickness 0.15)
					)
					(justify left bottom)
					(hide yes)
				)
			)
			(property "Val" "2u2"
				(at 20.32 -7.62 0)
				(effects
					(font
						(size 1.27 1.27)
						(thickness 0.15)
					)
					(justify left bottom)
				)
			)
			(property "Voltage" ""
				(at 20.32 -27.94 0)
				(effects
					(font
						(size 1.27 1.27)
					)
					(justify left bottom)
					(hide yes)
				)
			)
			(property "Dielectric" ""
				(at 20.32 -30.48 0)
				(effects
					(font
						(size 1.27 1.27)
					)
					(justify left bottom)
					(hide yes)
				)
			)
			(property "ki_keywords" "0402, SMT, CAPACITOR, PASSIVE, CERAMIC, MLCC"
				(at 0 0 0)
				(effects
					(font
						(size 1.27 1.27)
					)
					(hide yes)
				)
			)
			(symbol "C_2u2_0402_0_1"
				(polyline
					(pts
						(xy 2.032 -1.524) (xy 2.032 1.524)
					)
					(stroke
						(width 0.3048)
						(type default)
					)
					(fill
						(type none)
					)
				)
				(polyline
					(pts
						(xy 3.048 -1.524) (xy 3.048 1.524)
					)
					(stroke
						(width 0.3302)
						(type default)
					)
					(fill
						(type none)
					)
				)
			)
			(symbol "C_2u2_0402_1_1"
				(pin passive line
					(at 0 0 0)
					(length 2.032)
					(name "~"
						(effects
							(font
								(size 1.27 1.27)
							)
						)
					)
					(number "1"
						(effects
							(font
								(size 1.27 1.27)
							)
						)
					)
				)
				(pin passive line
					(at 5.08 0 180)
					(length 2.032)
					(name "~"
						(effects
							(font
								(size 1.27 1.27)
							)
						)
					)
					(number "2"
						(effects
							(font
								(size 1.27 1.27)
							)
						)
					)
				)
			)
		)
	(symbol "antmicroCapacitors0402:C_33p_0402"
			(pin_numbers hide)
			(pin_names hide)
			(exclude_from_sim no)
			(in_bom yes)
			(on_board yes)
			(property "Reference" "C"
				(at 20.32 -5.08 0)
				(effects
					(font
						(size 1.27 1.27)
						(thickness 0.15)
					)
					(justify left bottom)
				)
			)
			(property "Value" "C_33p_0402"
				(at 20.32 -10.16 0)
				(effects
					(font
						(size 1.27 1.27)
						(thickness 0.15)
					)
					(justify left bottom)
					(hide yes)
				)
			)
			(property "Footprint" "antmicro-footprints:C_0402_1005Metric"
				(at 20.32 -12.7 0)
				(effects
					(font
						(size 1.27 1.27)
						(thickness 0.15)
					)
					(justify left bottom)
					(hide yes)
				)
			)
			(property "Datasheet" "https://spicat.kyocera-avx.com/product/mlcc/chartview/04025A330FAT2A/"
				(at 20.32 -15.24 0)
				(effects
					(font
						(size 1.27 1.27)
						(thickness 0.15)
					)
					(justify left bottom)
					(hide yes)
				)
			)
			(property "Description" "SMD Multilayer Ceramic Capacitor, 33 pF, 50 V, 0402 [1005 Metric], ± 5%, C0G / NP0, MC"
				(at 0 0 0)
				(effects
					(font
						(size 1.27 1.27)
					)
					(hide yes)
				)
			)
			(property "MPN" "04025A330FAT2A"
				(at 20.32 -17.78 0)
				(effects
					(font
						(size 1.27 1.27)
						(thickness 0.15)
					)
					(justify left bottom)
					(hide yes)
				)
			)
			(property "Manufacturer" "KYOCERA AVX"
				(at 20.32 -20.32 0)
				(effects
					(font
						(size 1.27 1.27)
						(thickness 0.15)
					)
					(justify left bottom)
					(hide yes)
				)
			)
			(property "License" "Apache-2.0"
				(at 20.32 -22.86 0)
				(effects
					(font
						(size 1.27 1.27)
						(thickness 0.15)
					)
					(justify left bottom)
					(hide yes)
				)
			)
			(property "Author" "Antmicro"
				(at 20.32 -25.4 0)
				(effects
					(font
						(size 1.27 1.27)
						(thickness 0.15)
					)
					(justify left bottom)
					(hide yes)
				)
			)
			(property "Val" "33p"
				(at 20.32 -7.62 0)
				(effects
					(font
						(size 1.27 1.27)
						(thickness 0.15)
					)
					(justify left bottom)
				)
			)
			(property "Voltage" ""
				(at 20.32 -27.94 0)
				(effects
					(font
						(size 1.27 1.27)
					)
					(justify left bottom)
					(hide yes)
				)
			)
			(property "Dielectric" ""
				(at 20.32 -30.48 0)
				(effects
					(font
						(size 1.27 1.27)
					)
					(justify left bottom)
					(hide yes)
				)
			)
			(property "ki_keywords" "0402, SMT, CAPACITOR, PASSIVE"
				(at 0 0 0)
				(effects
					(font
						(size 1.27 1.27)
					)
					(hide yes)
				)
			)
			(symbol "C_33p_0402_0_1"
				(polyline
					(pts
						(xy 2.032 -1.524) (xy 2.032 1.524)
					)
					(stroke
						(width 0.3048)
						(type default)
					)
					(fill
						(type none)
					)
				)
				(polyline
					(pts
						(xy 3.048 -1.524) (xy 3.048 1.524)
					)
					(stroke
						(width 0.3302)
						(type default)
					)
					(fill
						(type none)
					)
				)
			)
			(symbol "C_33p_0402_1_1"
				(pin passive line
					(at 0 0 0)
					(length 2.032)
					(name "~"
						(effects
							(font
								(size 1.27 1.27)
							)
						)
					)
					(number "1"
						(effects
							(font
								(size 1.27 1.27)
							)
						)
					)
				)
				(pin passive line
					(at 5.08 0 180)
					(length 2.032)
					(name "~"
						(effects
							(font
								(size 1.27 1.27)
							)
						)
					)
					(number "2"
						(effects
							(font
								(size 1.27 1.27)
							)
						)
					)
				)
			)
		)
	(symbol "antmicroCapacitors0402:C_4n7_0402"
			(pin_numbers hide)
			(pin_names hide)
			(exclude_from_sim no)
			(in_bom yes)
			(on_board yes)
			(property "Reference" "C"
				(at 20.32 -5.08 0)
				(effects
					(font
						(size 1.27 1.27)
						(thickness 0.15)
					)
					(justify left bottom)
				)
			)
			(property "Value" "C_4n7_0402"
				(at 20.32 -10.16 0)
				(effects
					(font
						(size 1.27 1.27)
						(thickness 0.15)
					)
					(justify left bottom)
					(hide yes)
				)
			)
			(property "Footprint" "antmicro-footprints:C_0402_1005Metric"
				(at 20.32 -12.7 0)
				(effects
					(font
						(size 1.27 1.27)
						(thickness 0.15)
					)
					(justify left bottom)
					(hide yes)
				)
			)
			(property "Datasheet" "https://product.tdk.com/en/search/capacitor/ceramic/mlcc/info?part_no=CGA2B3X7S2A472K050BB"
				(at 20.32 -15.24 0)
				(effects
					(font
						(size 1.27 1.27)
						(thickness 0.15)
					)
					(justify left bottom)
					(hide yes)
				)
			)
			(property "Description" "SMD Multilayer Ceramic Capacitor, 4700 pF, 100 V, 0402 [1005 Metric], ± 10%, X7S, CGA"
				(at 0 0 0)
				(effects
					(font
						(size 1.27 1.27)
					)
					(hide yes)
				)
			)
			(property "MPN" "CGA2B3X7S2A472K050BB"
				(at 20.32 -17.78 0)
				(effects
					(font
						(size 1.27 1.27)
						(thickness 0.15)
					)
					(justify left bottom)
					(hide yes)
				)
			)
			(property "Manufacturer" "TDK"
				(at 20.32 -20.32 0)
				(effects
					(font
						(size 1.27 1.27)
						(thickness 0.15)
					)
					(justify left bottom)
					(hide yes)
				)
			)
			(property "License" "Apache-2.0"
				(at 20.32 -22.86 0)
				(effects
					(font
						(size 1.27 1.27)
						(thickness 0.15)
					)
					(justify left bottom)
					(hide yes)
				)
			)
			(property "Author" "Antmicro"
				(at 20.32 -25.4 0)
				(effects
					(font
						(size 1.27 1.27)
						(thickness 0.15)
					)
					(justify left bottom)
					(hide yes)
				)
			)
			(property "Val" "4n7"
				(at 20.32 -7.62 0)
				(effects
					(font
						(size 1.27 1.27)
						(thickness 0.15)
					)
					(justify left bottom)
				)
			)
			(property "Voltage" ""
				(at 20.32 -27.94 0)
				(effects
					(font
						(size 1.27 1.27)
					)
					(justify left bottom)
					(hide yes)
				)
			)
			(property "Dielectric" ""
				(at 20.32 -30.48 0)
				(effects
					(font
						(size 1.27 1.27)
					)
					(justify left bottom)
					(hide yes)
				)
			)
			(property "ki_keywords" "0402, SMT, CAPACITOR, PASSIVE, CERAMIC, MLCC"
				(at 0 0 0)
				(effects
					(font
						(size 1.27 1.27)
					)
					(hide yes)
				)
			)
			(symbol "C_4n7_0402_0_1"
				(polyline
					(pts
						(xy 2.032 -1.524) (xy 2.032 1.524)
					)
					(stroke
						(width 0.3048)
						(type default)
					)
					(fill
						(type none)
					)
				)
				(polyline
					(pts
						(xy 3.048 -1.524) (xy 3.048 1.524)
					)
					(stroke
						(width 0.3302)
						(type default)
					)
					(fill
						(type none)
					)
				)
			)
			(symbol "C_4n7_0402_1_1"
				(pin passive line
					(at 0 0 0)
					(length 2.032)
					(name "~"
						(effects
							(font
								(size 1.27 1.27)
							)
						)
					)
					(number "1"
						(effects
							(font
								(size 1.27 1.27)
							)
						)
					)
				)
				(pin passive line
					(at 5.08 0 180)
					(length 2.032)
					(name "~"
						(effects
							(font
								(size 1.27 1.27)
							)
						)
					)
					(number "2"
						(effects
							(font
								(size 1.27 1.27)
							)
						)
					)
				)
			)
		)
	(symbol "antmicroCapacitors0402:C_4u7_25V_0402"
			(pin_numbers hide)
			(pin_names hide)
			(exclude_from_sim no)
			(in_bom yes)
			(on_board yes)
			(property "Reference" "C"
				(at 20.32 -5.08 0)
				(effects
					(font
						(size 1.27 1.27)
						(thickness 0.15)
					)
					(justify left bottom)
				)
			)
			(property "Value" "C_4u7_25V_0402"
				(at 20.32 -10.16 0)
				(effects
					(font
						(size 1.27 1.27)
						(thickness 0.15)
					)
					(justify left bottom)
					(hide yes)
				)
			)
			(property "Footprint" "antmicro-footprints:C_0402_1005Metric"
				(at 20.32 -12.7 0)
				(effects
					(font
						(size 1.27 1.27)
						(thickness 0.15)
					)
					(justify left bottom)
					(hide yes)
				)
			)
			(property "Datasheet" "https://www.murata.com/products/productdetail?partno=GRM155C61E475ME15%23"
				(at 20.32 -15.24 0)
				(effects
					(font
						(size 1.27 1.27)
						(thickness 0.15)
					)
					(justify left bottom)
					(hide yes)
				)
			)
			(property "Description" "SMD Multilayer Ceramic Capacitor"
				(at 0 0 0)
				(effects
					(font
						(size 1.27 1.27)
					)
					(hide yes)
				)
			)
			(property "MPN" "GRM155C61E475ME15J"
				(at 20.32 -17.78 0)
				(effects
					(font
						(size 1.27 1.27)
						(thickness 0.15)
					)
					(justify left bottom)
					(hide yes)
				)
			)
			(property "Manufacturer" "Murata"
				(at 20.32 -20.32 0)
				(effects
					(font
						(size 1.27 1.27)
						(thickness 0.15)
					)
					(justify left bottom)
					(hide yes)
				)
			)
			(property "License" "Apache-2.0"
				(at 20.32 -22.86 0)
				(effects
					(font
						(size 1.27 1.27)
						(thickness 0.15)
					)
					(justify left bottom)
					(hide yes)
				)
			)
			(property "Author" "Antmicro"
				(at 20.32 -25.4 0)
				(effects
					(font
						(size 1.27 1.27)
						(thickness 0.15)
					)
					(justify left bottom)
					(hide yes)
				)
			)
			(property "Val" "4u7"
				(at 20.32 -7.62 0)
				(effects
					(font
						(size 1.27 1.27)
						(thickness 0.15)
					)
					(justify left bottom)
				)
			)
			(property "Voltage" "25V"
				(at 20.32 -27.94 0)
				(effects
					(font
						(size 1.27 1.27)
					)
					(justify left bottom)
					(hide yes)
				)
			)
			(property "Dielectric" "X5S"
				(at 20.32 -30.48 0)
				(effects
					(font
						(size 1.27 1.27)
					)
					(justify left bottom)
					(hide yes)
				)
			)
			(property "ki_keywords" "0402, SMT, CAPACITOR, PASSIVE, CERAMIC"
				(at 0 0 0)
				(effects
					(font
						(size 1.27 1.27)
					)
					(hide yes)
				)
			)
			(symbol "C_4u7_25V_0402_0_1"
				(polyline
					(pts
						(xy 2.032 -1.524) (xy 2.032 1.524)
					)
					(stroke
						(width 0.3048)
						(type default)
					)
					(fill
						(type none)
					)
				)
				(polyline
					(pts
						(xy 3.048 -1.524) (xy 3.048 1.524)
					)
					(stroke
						(width 0.3302)
						(type default)
					)
					(fill
						(type none)
					)
				)
			)
			(symbol "C_4u7_25V_0402_1_1"
				(pin passive line
					(at 0 0 0)
					(length 2.032)
					(name "~"
						(effects
							(font
								(size 1.27 1.27)
							)
						)
					)
					(number "1"
						(effects
							(font
								(size 1.27 1.27)
							)
						)
					)
				)
				(pin passive line
					(at 5.08 0 180)
					(length 2.032)
					(name "~"
						(effects
							(font
								(size 1.27 1.27)
							)
						)
					)
					(number "2"
						(effects
							(font
								(size 1.27 1.27)
							)
						)
					)
				)
			)
		)
	(symbol "antmicroCapacitors0603:C_10u_0603"
			(pin_numbers hide)
			(pin_names hide)
			(exclude_from_sim no)
			(in_bom yes)
			(on_board yes)
			(property "Reference" "C"
				(at 20.32 -5.08 0)
				(effects
					(font
						(size 1.27 1.27)
						(thickness 0.15)
					)
					(justify left bottom)
				)
			)
			(property "Value" "C_10u_0603"
				(at 20.32 -10.16 0)
				(effects
					(font
						(size 1.27 1.27)
						(thickness 0.15)
					)
					(justify left bottom)
					(hide yes)
				)
			)
			(property "Footprint" "antmicro-footprints:C_0603_1608Metric"
				(at 20.32 -12.7 0)
				(effects
					(font
						(size 1.27 1.27)
						(thickness 0.15)
					)
					(justify left bottom)
					(hide yes)
				)
			)
			(property "Datasheet" "https://www.murata.com/products/productdetail?partno=GRM188R61A106KE69%23"
				(at 20.32 -15.24 0)
				(effects
					(font
						(size 1.27 1.27)
						(thickness 0.15)
					)
					(justify left bottom)
					(hide yes)
				)
			)
			(property "Description" "SMD Multilayer Ceramic Capacitor, 10 µF, 10 V, 0603 [1608 Metric], ± 10%, X5R, GRM Series"
				(at 0 0 0)
				(effects
					(font
						(size 1.27 1.27)
					)
					(hide yes)
				)
			)
			(property "MPN" "GRM188R61A106KE69D"
				(at 20.32 -17.78 0)
				(effects
					(font
						(size 1.27 1.27)
						(thickness 0.15)
					)
					(justify left bottom)
					(hide yes)
				)
			)
			(property "Manufacturer" "Murata"
				(at 20.32 -20.32 0)
				(effects
					(font
						(size 1.27 1.27)
						(thickness 0.15)
					)
					(justify left bottom)
					(hide yes)
				)
			)
			(property "License" "Apache-2.0"
				(at 20.32 -22.86 0)
				(effects
					(font
						(size 1.27 1.27)
						(thickness 0.15)
					)
					(justify left bottom)
					(hide yes)
				)
			)
			(property "Author" "Antmicro"
				(at 20.32 -25.4 0)
				(effects
					(font
						(size 1.27 1.27)
						(thickness 0.15)
					)
					(justify left bottom)
					(hide yes)
				)
			)
			(property "Val" "10u"
				(at 20.32 -7.62 0)
				(effects
					(font
						(size 1.27 1.27)
						(thickness 0.15)
					)
					(justify left bottom)
				)
			)
			(property "Voltage" ""
				(at 20.32 -27.94 0)
				(effects
					(font
						(size 1.27 1.27)
					)
					(justify left bottom)
					(hide yes)
				)
			)
			(property "Dielectric" "template_dielectric"
				(at 20.32 -30.48 0)
				(effects
					(font
						(size 1.27 1.27)
					)
					(justify left bottom)
					(hide yes)
				)
			)
			(property "ki_keywords" "0603, SMT, CAPACITOR, PASSIVE, CERAMIC, MLCC"
				(at 0 0 0)
				(effects
					(font
						(size 1.27 1.27)
					)
					(hide yes)
				)
			)
			(symbol "C_10u_0603_0_1"
				(polyline
					(pts
						(xy 2.032 -1.524) (xy 2.032 1.524)
					)
					(stroke
						(width 0.3048)
						(type default)
					)
					(fill
						(type none)
					)
				)
				(polyline
					(pts
						(xy 3.048 -1.524) (xy 3.048 1.524)
					)
					(stroke
						(width 0.3302)
						(type default)
					)
					(fill
						(type none)
					)
				)
			)
			(symbol "C_10u_0603_1_1"
				(pin passive line
					(at 0 0 0)
					(length 2.032)
					(name "~"
						(effects
							(font
								(size 1.27 1.27)
							)
						)
					)
					(number "1"
						(effects
							(font
								(size 1.27 1.27)
							)
						)
					)
				)
				(pin passive line
					(at 5.08 0 180)
					(length 2.032)
					(name "~"
						(effects
							(font
								(size 1.27 1.27)
							)
						)
					)
					(number "2"
						(effects
							(font
								(size 1.27 1.27)
							)
						)
					)
				)
			)
		)
	(symbol "antmicroCapacitors0603:C_22u_0603"
			(pin_numbers hide)
			(pin_names hide)
			(exclude_from_sim no)
			(in_bom yes)
			(on_board yes)
			(property "Reference" "C"
				(at 20.32 -5.08 0)
				(effects
					(font
						(size 1.27 1.27)
						(thickness 0.15)
					)
					(justify left bottom)
				)
			)
			(property "Value" "C_22u_0603"
				(at 20.32 -10.16 0)
				(effects
					(font
						(size 1.27 1.27)
						(thickness 0.15)
					)
					(justify left bottom)
					(hide yes)
				)
			)
			(property "Footprint" "antmicro-footprints:C_0603_1608Metric"
				(at 20.32 -12.7 0)
				(effects
					(font
						(size 1.27 1.27)
						(thickness 0.15)
					)
					(justify left bottom)
					(hide yes)
				)
			)
			(property "Datasheet" "https://www.murata.com/products/productdetail?partno=GRM188R60J226MEA0%23"
				(at 20.32 -15.24 0)
				(effects
					(font
						(size 1.27 1.27)
						(thickness 0.15)
					)
					(justify left bottom)
					(hide yes)
				)
			)
			(property "Description" "SMD Multilayer Ceramic Capacitor, 22 µF, 6.3 V, 0603 [1608 Metric], ± 20%, X5R, GRM Series"
				(at 0 0 0)
				(effects
					(font
						(size 1.27 1.27)
					)
					(hide yes)
				)
			)
			(property "MPN" "GRM188R60J226MEA0D"
				(at 20.32 -17.78 0)
				(effects
					(font
						(size 1.27 1.27)
						(thickness 0.15)
					)
					(justify left bottom)
					(hide yes)
				)
			)
			(property "Manufacturer" "Murata"
				(at 20.32 -20.32 0)
				(effects
					(font
						(size 1.27 1.27)
						(thickness 0.15)
					)
					(justify left bottom)
					(hide yes)
				)
			)
			(property "License" "Apache-2.0"
				(at 20.32 -22.86 0)
				(effects
					(font
						(size 1.27 1.27)
						(thickness 0.15)
					)
					(justify left bottom)
					(hide yes)
				)
			)
			(property "Author" "Antmicro"
				(at 20.32 -25.4 0)
				(effects
					(font
						(size 1.27 1.27)
						(thickness 0.15)
					)
					(justify left bottom)
					(hide yes)
				)
			)
			(property "Val" "22u"
				(at 20.32 -7.62 0)
				(effects
					(font
						(size 1.27 1.27)
						(thickness 0.15)
					)
					(justify left bottom)
				)
			)
			(property "Voltage" ""
				(at 20.32 -27.94 0)
				(effects
					(font
						(size 1.27 1.27)
					)
					(justify left bottom)
					(hide yes)
				)
			)
			(property "Dielectric" ""
				(at 20.32 -30.48 0)
				(effects
					(font
						(size 1.27 1.27)
					)
					(justify left bottom)
					(hide yes)
				)
			)
			(property "ki_keywords" "0603, SMT, CAPACITOR, PASSIVE, CERAMIC, MLCC"
				(at 0 0 0)
				(effects
					(font
						(size 1.27 1.27)
					)
					(hide yes)
				)
			)
			(symbol "C_22u_0603_0_1"
				(polyline
					(pts
						(xy 2.032 -1.524) (xy 2.032 1.524)
					)
					(stroke
						(width 0.3048)
						(type default)
					)
					(fill
						(type none)
					)
				)
				(polyline
					(pts
						(xy 3.048 -1.524) (xy 3.048 1.524)
					)
					(stroke
						(width 0.3302)
						(type default)
					)
					(fill
						(type none)
					)
				)
			)
			(symbol "C_22u_0603_1_1"
				(pin passive line
					(at 0 0 0)
					(length 2.032)
					(name "~"
						(effects
							(font
								(size 1.27 1.27)
							)
						)
					)
					(number "1"
						(effects
							(font
								(size 1.27 1.27)
							)
						)
					)
				)
				(pin passive line
					(at 5.08 0 180)
					(length 2.032)
					(name "~"
						(effects
							(font
								(size 1.27 1.27)
							)
						)
					)
					(number "2"
						(effects
							(font
								(size 1.27 1.27)
							)
						)
					)
				)
			)
		)
	(symbol "antmicroCapacitors0603:C_22u_16V_0603"
			(pin_numbers hide)
			(pin_names hide)
			(exclude_from_sim no)
			(in_bom yes)
			(on_board yes)
			(property "Reference" "C"
				(at 20.32 -5.08 0)
				(effects
					(font
						(size 1.27 1.27)
						(thickness 0.15)
					)
					(justify left bottom)
				)
			)
			(property "Value" "C_22u_16V_0603"
				(at 20.32 -10.16 0)
				(effects
					(font
						(size 1.27 1.27)
						(thickness 0.15)
					)
					(justify left bottom)
					(hide yes)
				)
			)
			(property "Footprint" "antmicro-footprints:C_0603_1608Metric"
				(at 20.32 -12.7 0)
				(effects
					(font
						(size 1.27 1.27)
						(thickness 0.15)
					)
					(justify left bottom)
					(hide yes)
				)
			)
			(property "Datasheet" "https://product.samsungsem.com/mlcc/CL10A226MO7JZN.do"
				(at 20.32 -15.24 0)
				(effects
					(font
						(size 1.27 1.27)
						(thickness 0.15)
					)
					(justify left bottom)
					(hide yes)
				)
			)
			(property "Description" "SMD Multilayer Ceramic Capacitor"
				(at 0 0 0)
				(effects
					(font
						(size 1.27 1.27)
					)
					(hide yes)
				)
			)
			(property "MPN" "CL10A226MO7JZNC"
				(at 20.32 -17.78 0)
				(effects
					(font
						(size 1.27 1.27)
						(thickness 0.15)
					)
					(justify left bottom)
					(hide yes)
				)
			)
			(property "Manufacturer" "Samsung Electro-Mechanics"
				(at 20.32 -20.32 0)
				(effects
					(font
						(size 1.27 1.27)
						(thickness 0.15)
					)
					(justify left bottom)
					(hide yes)
				)
			)
			(property "License" "Apache-2.0"
				(at 20.32 -22.86 0)
				(effects
					(font
						(size 1.27 1.27)
						(thickness 0.15)
					)
					(justify left bottom)
					(hide yes)
				)
			)
			(property "Author" "Antmicro"
				(at 20.32 -25.4 0)
				(effects
					(font
						(size 1.27 1.27)
						(thickness 0.15)
					)
					(justify left bottom)
					(hide yes)
				)
			)
			(property "Val" "22u"
				(at 20.32 -7.62 0)
				(effects
					(font
						(size 1.27 1.27)
						(thickness 0.15)
					)
					(justify left bottom)
				)
			)
			(property "Voltage" "16V"
				(at 20.32 -27.94 0)
				(effects
					(font
						(size 1.27 1.27)
					)
					(justify left bottom)
					(hide yes)
				)
			)
			(property "Dielectric" ""
				(at 20.32 -30.48 0)
				(effects
					(font
						(size 1.27 1.27)
					)
					(justify left bottom)
					(hide yes)
				)
			)
			(property "ki_keywords" "0603, SMT, CAPACITOR, PASSIVE, CERAMIC"
				(at 0 0 0)
				(effects
					(font
						(size 1.27 1.27)
					)
					(hide yes)
				)
			)
			(symbol "C_22u_16V_0603_0_1"
				(polyline
					(pts
						(xy 2.032 -1.524) (xy 2.032 1.524)
					)
					(stroke
						(width 0.3048)
						(type default)
					)
					(fill
						(type none)
					)
				)
				(polyline
					(pts
						(xy 3.048 -1.524) (xy 3.048 1.524)
					)
					(stroke
						(width 0.3302)
						(type default)
					)
					(fill
						(type none)
					)
				)
			)
			(symbol "C_22u_16V_0603_1_1"
				(pin passive line
					(at 0 0 0)
					(length 2.032)
					(name "~"
						(effects
							(font
								(size 1.27 1.27)
							)
						)
					)
					(number "1"
						(effects
							(font
								(size 1.27 1.27)
							)
						)
					)
				)
				(pin passive line
					(at 5.08 0 180)
					(length 2.032)
					(name "~"
						(effects
							(font
								(size 1.27 1.27)
							)
						)
					)
					(number "2"
						(effects
							(font
								(size 1.27 1.27)
							)
						)
					)
				)
			)
		)
	(symbol "antmicroCapacitorsmisc:C_10u_0805_35V"
			(pin_numbers hide)
			(pin_names hide)
			(exclude_from_sim no)
			(in_bom yes)
			(on_board yes)
			(property "Reference" "C"
				(at 20.32 -5.08 0)
				(effects
					(font
						(size 1.27 1.27)
						(thickness 0.15)
					)
					(justify left bottom)
				)
			)
			(property "Value" "C_10u_0805_35V"
				(at 20.32 -10.16 0)
				(effects
					(font
						(size 1.27 1.27)
						(thickness 0.15)
					)
					(justify left bottom)
					(hide yes)
				)
			)
			(property "Footprint" "antmicro-footprints:C_0805_2012Metric"
				(at 20.32 -12.7 0)
				(effects
					(font
						(size 1.27 1.27)
						(thickness 0.15)
					)
					(justify left bottom)
					(hide yes)
				)
			)
			(property "Datasheet" "https://www.murata.com/products/productdetail?partno=GRM21BR6YA106KE43%23"
				(at 20.32 -15.24 0)
				(effects
					(font
						(size 1.27 1.27)
						(thickness 0.15)
					)
					(justify left bottom)
					(hide yes)
				)
			)
			(property "Description" "SMD Multilayer Ceramic Capacitor, 10 µF, 35 V, 0805 [2012 Metric], ± 10%, X5R, GRM Series"
				(at 0 0 0)
				(effects
					(font
						(size 1.27 1.27)
					)
					(hide yes)
				)
			)
			(property "MPN" "GRM21BR6YA106KE43L"
				(at 20.32 -17.78 0)
				(effects
					(font
						(size 1.27 1.27)
						(thickness 0.15)
					)
					(justify left bottom)
					(hide yes)
				)
			)
			(property "Manufacturer" "Murata"
				(at 20.32 -20.32 0)
				(effects
					(font
						(size 1.27 1.27)
						(thickness 0.15)
					)
					(justify left bottom)
					(hide yes)
				)
			)
			(property "License" "Apache-2.0"
				(at 20.32 -22.86 0)
				(effects
					(font
						(size 1.27 1.27)
						(thickness 0.15)
					)
					(justify left bottom)
					(hide yes)
				)
			)
			(property "Author" "Antmicro"
				(at 20.32 -25.4 0)
				(effects
					(font
						(size 1.27 1.27)
						(thickness 0.15)
					)
					(justify left bottom)
					(hide yes)
				)
			)
			(property "Val" "10u"
				(at 20.32 -7.62 0)
				(effects
					(font
						(size 1.27 1.27)
						(thickness 0.15)
					)
					(justify left bottom)
				)
			)
			(property "Voltage" "35V"
				(at 20.32 -27.94 0)
				(effects
					(font
						(size 1.27 1.27)
					)
					(justify left bottom)
					(hide yes)
				)
			)
			(property "Dielectric" ""
				(at 20.32 -30.48 0)
				(effects
					(font
						(size 1.27 1.27)
					)
					(justify left bottom)
					(hide yes)
				)
			)
			(property "ki_keywords" "0805, SMT, CAPACITOR, PASSIVE"
				(at 0 0 0)
				(effects
					(font
						(size 1.27 1.27)
					)
					(hide yes)
				)
			)
			(symbol "C_10u_0805_35V_0_1"
				(polyline
					(pts
						(xy 2.032 -1.524) (xy 2.032 1.524)
					)
					(stroke
						(width 0.3048)
						(type default)
					)
					(fill
						(type none)
					)
				)
				(polyline
					(pts
						(xy 3.048 -1.524) (xy 3.048 1.524)
					)
					(stroke
						(width 0.3302)
						(type default)
					)
					(fill
						(type none)
					)
				)
			)
			(symbol "C_10u_0805_35V_1_1"
				(pin passive line
					(at 0 0 0)
					(length 2.032)
					(name "~"
						(effects
							(font
								(size 1.27 1.27)
							)
						)
					)
					(number "1"
						(effects
							(font
								(size 1.27 1.27)
							)
						)
					)
				)
				(pin passive line
					(at 5.08 0 180)
					(length 2.032)
					(name "~"
						(effects
							(font
								(size 1.27 1.27)
							)
						)
					)
					(number "2"
						(effects
							(font
								(size 1.27 1.27)
							)
						)
					)
				)
			)
		)
	(symbol "antmicroCapacitorsmisc:C_22u_1206_35V"
			(pin_numbers hide)
			(pin_names hide)
			(exclude_from_sim no)
			(in_bom yes)
			(on_board yes)
			(property "Reference" "C"
				(at 20.32 -5.08 0)
				(effects
					(font
						(size 1.27 1.27)
						(thickness 0.15)
					)
					(justify left bottom)
				)
			)
			(property "Value" "C_22u_1206_35V"
				(at 20.32 -10.16 0)
				(effects
					(font
						(size 1.27 1.27)
						(thickness 0.15)
					)
					(justify left bottom)
					(hide yes)
				)
			)
			(property "Footprint" "antmicro-footprints:C_1206_3216Metric"
				(at 20.32 -12.7 0)
				(effects
					(font
						(size 1.27 1.27)
						(thickness 0.15)
					)
					(justify left bottom)
					(hide yes)
				)
			)
			(property "Datasheet" "https://product.tdk.com/en/search/capacitor/ceramic/mlcc/info?part_no=3216X5R1V226M160AC"
				(at 20.32 -15.24 0)
				(effects
					(font
						(size 1.27 1.27)
						(thickness 0.15)
					)
					(justify left bottom)
					(hide yes)
				)
			)
			(property "Description" "SMD Multilayer Ceramic Capacitors, 22µF, 35V, X5R, 1206 [2316 Metric], 20% "
				(at 0 0 0)
				(effects
					(font
						(size 1.27 1.27)
					)
					(hide yes)
				)
			)
			(property "MPN" "3216X5R1V226M160AC"
				(at 20.32 -17.78 0)
				(effects
					(font
						(size 1.27 1.27)
						(thickness 0.15)
					)
					(justify left bottom)
					(hide yes)
				)
			)
			(property "Manufacturer" "TDK"
				(at 20.32 -20.32 0)
				(effects
					(font
						(size 1.27 1.27)
						(thickness 0.15)
					)
					(justify left bottom)
					(hide yes)
				)
			)
			(property "License" "Apache-2.0"
				(at 20.32 -22.86 0)
				(effects
					(font
						(size 1.27 1.27)
						(thickness 0.15)
					)
					(justify left bottom)
					(hide yes)
				)
			)
			(property "Author" "Antmicro"
				(at 20.32 -25.4 0)
				(effects
					(font
						(size 1.27 1.27)
						(thickness 0.15)
					)
					(justify left bottom)
					(hide yes)
				)
			)
			(property "Val" "22u"
				(at 20.32 -7.62 0)
				(effects
					(font
						(size 1.27 1.27)
						(thickness 0.15)
					)
					(justify left bottom)
				)
			)
			(property "Voltage" "35V"
				(at 20.32 -27.94 0)
				(effects
					(font
						(size 1.27 1.27)
					)
					(justify left bottom)
					(hide yes)
				)
			)
			(property "Dielectric" ""
				(at 20.32 -30.48 0)
				(effects
					(font
						(size 1.27 1.27)
					)
					(justify left bottom)
					(hide yes)
				)
			)
			(property "ki_keywords" "1206, SMT, CAPACITOR, PASSIVE, CERAMIC, MLCC"
				(at 0 0 0)
				(effects
					(font
						(size 1.27 1.27)
					)
					(hide yes)
				)
			)
			(symbol "C_22u_1206_35V_0_1"
				(polyline
					(pts
						(xy 2.032 -1.524) (xy 2.032 1.524)
					)
					(stroke
						(width 0.3048)
						(type default)
					)
					(fill
						(type none)
					)
				)
				(polyline
					(pts
						(xy 3.048 -1.524) (xy 3.048 1.524)
					)
					(stroke
						(width 0.3302)
						(type default)
					)
					(fill
						(type none)
					)
				)
			)
			(symbol "C_22u_1206_35V_1_1"
				(pin passive line
					(at 0 0 0)
					(length 2.032)
					(name "~"
						(effects
							(font
								(size 1.27 1.27)
							)
						)
					)
					(number "1"
						(effects
							(font
								(size 1.27 1.27)
							)
						)
					)
				)
				(pin passive line
					(at 5.08 0 180)
					(length 2.032)
					(name "~"
						(effects
							(font
								(size 1.27 1.27)
							)
						)
					)
					(number "2"
						(effects
							(font
								(size 1.27 1.27)
							)
						)
					)
				)
			)
		)
	(symbol "antmicroCapacitorsmisc:C_22u_25V_0805"
			(pin_numbers hide)
			(pin_names hide)
			(exclude_from_sim no)
			(in_bom yes)
			(on_board yes)
			(property "Reference" "C"
				(at 20.32 -5.08 0)
				(effects
					(font
						(size 1.27 1.27)
						(thickness 0.15)
					)
					(justify left bottom)
				)
			)
			(property "Value" "C_22u_25V_0805"
				(at 20.32 -10.16 0)
				(effects
					(font
						(size 1.27 1.27)
						(thickness 0.15)
					)
					(justify left bottom)
					(hide yes)
				)
			)
			(property "Footprint" "antmicro-footprints:C_0805_2012Metric"
				(at 20.32 -12.7 0)
				(effects
					(font
						(size 1.27 1.27)
						(thickness 0.15)
					)
					(justify left bottom)
					(hide yes)
				)
			)
			(property "Datasheet" "https://product.samsungsem.com/mlcc/CL21A226MAYNNN.do"
				(at 20.32 -15.24 0)
				(effects
					(font
						(size 1.27 1.27)
						(thickness 0.15)
					)
					(justify left bottom)
					(hide yes)
				)
			)
			(property "Description" "SMT Multilayer Ceramic Capacitor, 22uF, +/-20%, 25V, X5R, 0805 [2012 Metric]"
				(at 0 0 0)
				(effects
					(font
						(size 1.27 1.27)
					)
					(hide yes)
				)
			)
			(property "MPN" "CL21A226MAYNNNE"
				(at 20.32 -17.78 0)
				(effects
					(font
						(size 1.27 1.27)
						(thickness 0.15)
					)
					(justify left bottom)
					(hide yes)
				)
			)
			(property "Manufacturer" "Samsung Electro-Mechanics"
				(at 20.32 -20.32 0)
				(effects
					(font
						(size 1.27 1.27)
						(thickness 0.15)
					)
					(justify left bottom)
					(hide yes)
				)
			)
			(property "License" "Apache-2.0"
				(at 20.32 -22.86 0)
				(effects
					(font
						(size 1.27 1.27)
						(thickness 0.15)
					)
					(justify left bottom)
					(hide yes)
				)
			)
			(property "Author" "Antmicro"
				(at 20.32 -25.4 0)
				(effects
					(font
						(size 1.27 1.27)
						(thickness 0.15)
					)
					(justify left bottom)
					(hide yes)
				)
			)
			(property "Val" "22u"
				(at 20.32 -7.62 0)
				(effects
					(font
						(size 1.27 1.27)
						(thickness 0.15)
					)
					(justify left bottom)
				)
			)
			(property "Voltage" "25V"
				(at 20.32 -27.94 0)
				(effects
					(font
						(size 1.27 1.27)
					)
					(justify left bottom)
				)
			)
			(property "Dielectric" "X5R"
				(at 20.32 -30.48 0)
				(effects
					(font
						(size 1.27 1.27)
					)
					(justify left bottom)
					(hide yes)
				)
			)
			(property "ki_keywords" "0805, SMT, CAPACITOR, PASSIVE"
				(at 0 0 0)
				(effects
					(font
						(size 1.27 1.27)
					)
					(hide yes)
				)
			)
			(symbol "C_22u_25V_0805_0_1"
				(polyline
					(pts
						(xy 2.032 -1.524) (xy 2.032 1.524)
					)
					(stroke
						(width 0.3048)
						(type default)
					)
					(fill
						(type none)
					)
				)
				(polyline
					(pts
						(xy 3.048 -1.524) (xy 3.048 1.524)
					)
					(stroke
						(width 0.3302)
						(type default)
					)
					(fill
						(type none)
					)
				)
			)
			(symbol "C_22u_25V_0805_1_1"
				(pin passive line
					(at 0 0 0)
					(length 2.032)
					(name "~"
						(effects
							(font
								(size 1.27 1.27)
							)
						)
					)
					(number "1"
						(effects
							(font
								(size 1.27 1.27)
							)
						)
					)
				)
				(pin passive line
					(at 5.08 0 180)
					(length 2.032)
					(name "~"
						(effects
							(font
								(size 1.27 1.27)
							)
						)
					)
					(number "2"
						(effects
							(font
								(size 1.27 1.27)
							)
						)
					)
				)
			)
		)
	(symbol "antmicroCapacitorspol:C_Pol_330u_16V_KYOCERA-AVX-TCJ-E"
			(pin_numbers hide)
			(pin_names hide)
			(exclude_from_sim no)
			(in_bom yes)
			(on_board yes)
			(property "Reference" "C"
				(at 13.97 0 0)
				(effects
					(font
						(size 1.27 1.27)
						(thickness 0.15)
					)
					(justify left bottom)
				)
			)
			(property "Value" "C_Pol_330u_16V_KYOCERA-AVX-TCJ-E"
				(at 13.97 -2.54 0)
				(effects
					(font
						(size 1.27 1.27)
						(thickness 0.15)
					)
					(justify left bottom)
					(hide yes)
				)
			)
			(property "Footprint" "antmicro-footprints:C_Pol_EIA-E"
				(at 13.97 -7.62 0)
				(effects
					(font
						(size 1.27 1.27)
						(thickness 0.15)
					)
					(justify left bottom)
					(hide yes)
				)
			)
			(property "Datasheet" "https://spicat.kyocera-avx.com/product/tan/chartview/TCJE337M016R0070E/"
				(at 13.97 -10.16 0)
				(effects
					(font
						(size 1.27 1.27)
						(thickness 0.15)
					)
					(justify left bottom)
					(hide yes)
				)
			)
			(property "Description" "Tantalum Capacitors - Polymer 16V 330uF 2917 20% ESR=70mOhms"
				(at 0 0 0)
				(effects
					(font
						(size 1.27 1.27)
					)
					(hide yes)
				)
			)
			(property "Val" "330u"
				(at 13.97 -5.08 0)
				(effects
					(font
						(size 1.27 1.27)
						(thickness 0.15)
					)
					(justify left bottom)
				)
			)
			(property "MPN" "TCJE337M016R0070E"
				(at 13.97 -12.7 0)
				(effects
					(font
						(size 1.27 1.27)
						(thickness 0.15)
					)
					(justify left bottom)
					(hide yes)
				)
			)
			(property "Manufacturer" "KYOCERA AVX"
				(at 13.97 -15.24 0)
				(effects
					(font
						(size 1.27 1.27)
						(thickness 0.15)
					)
					(justify left bottom)
					(hide yes)
				)
			)
			(property "License" "Apache-2.0"
				(at 13.97 -17.78 0)
				(effects
					(font
						(size 1.27 1.27)
						(thickness 0.15)
					)
					(justify left bottom)
					(hide yes)
				)
			)
			(property "Author" "Antmicro"
				(at 13.97 -20.32 0)
				(effects
					(font
						(size 1.27 1.27)
						(thickness 0.15)
					)
					(justify left bottom)
					(hide yes)
				)
			)
			(property "Voltage" "16V"
				(at 13.97 -22.86 0)
				(effects
					(font
						(size 1.27 1.27)
					)
					(justify left bottom)
					(hide yes)
				)
			)
			(property "Dielectric" "template_dielectric"
				(at 13.97 -25.4 0)
				(effects
					(font
						(size 1.27 1.27)
					)
					(justify left bottom)
					(hide yes)
				)
			)
			(property "ki_keywords" "SMT, CAPACITOR, PASSIVE, POLARIZED"
				(at 0 0 0)
				(effects
					(font
						(size 1.27 1.27)
					)
					(hide yes)
				)
			)
			(symbol "C_Pol_330u_16V_KYOCERA-AVX-TCJ-E_0_1"
				(polyline
					(pts
						(xy 0.9652 1.27) (xy 0.9652 1.778)
					)
					(stroke
						(width 0)
						(type default)
					)
					(fill
						(type none)
					)
				)
				(polyline
					(pts
						(xy 1.2192 1.524) (xy 0.7112 1.524)
					)
					(stroke
						(width 0)
						(type default)
					)
					(fill
						(type none)
					)
				)
				(rectangle
					(start 1.905 -1.524)
					(end 2.286 1.524)
					(stroke
						(width 0)
						(type default)
					)
					(fill
						(type none)
					)
				)
				(rectangle
					(start 2.921 -1.524)
					(end 3.302 1.524)
					(stroke
						(width 0)
						(type default)
					)
					(fill
						(type outline)
					)
				)
			)
			(symbol "C_Pol_330u_16V_KYOCERA-AVX-TCJ-E_1_1"
				(pin passive line
					(at 0 0 0)
					(length 1.8542)
					(name "~"
						(effects
							(font
								(size 1.27 1.27)
							)
						)
					)
					(number "1"
						(effects
							(font
								(size 1.27 1.27)
							)
						)
					)
				)
				(pin passive line
					(at 5.08 0 180)
					(length 1.8542)
					(name "~"
						(effects
							(font
								(size 1.27 1.27)
							)
						)
					)
					(number "2"
						(effects
							(font
								(size 1.27 1.27)
							)
						)
					)
				)
			)
		)
	(symbol "antmicroCapacitorspol:C_Pol_330u_6.3V_KEMET-T520-B"
			(pin_numbers hide)
			(pin_names hide)
			(exclude_from_sim no)
			(in_bom yes)
			(on_board yes)
			(property "Reference" "C"
				(at 13.97 0 0)
				(effects
					(font
						(size 1.27 1.27)
						(thickness 0.15)
					)
					(justify left bottom)
				)
			)
			(property "Value" "C_Pol_330u_6.3V_KEMET-T520-B"
				(at 13.97 -2.54 0)
				(effects
					(font
						(size 1.27 1.27)
						(thickness 0.15)
					)
					(justify left bottom)
					(hide yes)
				)
			)
			(property "Footprint" "antmicro-footprints:C_Pol_EIA-B"
				(at 13.97 -7.62 0)
				(effects
					(font
						(size 1.27 1.27)
						(thickness 0.15)
					)
					(justify left bottom)
					(hide yes)
				)
			)
			(property "Datasheet" "https://www.kemet.com/en/us/capacitors/product/T520B337M006ATE040.html"
				(at 13.97 -10.16 0)
				(effects
					(font
						(size 1.27 1.27)
						(thickness 0.15)
					)
					(justify left bottom)
					(hide yes)
				)
			)
			(property "Description" "Tantalum Polymer Capacitor, KO-CAP®, 330 µF, ± 20%, 6.3 V, B, 0.04 ohm, 1411 [3528 Metric]"
				(at 0 0 0)
				(effects
					(font
						(size 1.27 1.27)
					)
					(hide yes)
				)
			)
			(property "Val" "330u"
				(at 13.97 -5.08 0)
				(effects
					(font
						(size 1.27 1.27)
						(thickness 0.15)
					)
					(justify left bottom)
				)
			)
			(property "MPN" "T520B337M006ATE040"
				(at 13.97 -12.7 0)
				(effects
					(font
						(size 1.27 1.27)
						(thickness 0.15)
					)
					(justify left bottom)
					(hide yes)
				)
			)
			(property "Manufacturer" "KEMET"
				(at 13.97 -15.24 0)
				(effects
					(font
						(size 1.27 1.27)
						(thickness 0.15)
					)
					(justify left bottom)
					(hide yes)
				)
			)
			(property "License" "Apache-2.0"
				(at 13.97 -17.78 0)
				(effects
					(font
						(size 1.27 1.27)
						(thickness 0.15)
					)
					(justify left bottom)
					(hide yes)
				)
			)
			(property "Author" "Antmicro"
				(at 13.97 -20.32 0)
				(effects
					(font
						(size 1.27 1.27)
						(thickness 0.15)
					)
					(justify left bottom)
					(hide yes)
				)
			)
			(property "Voltage" "6.3V"
				(at 13.97 -22.86 0)
				(effects
					(font
						(size 1.27 1.27)
					)
					(justify left bottom)
					(hide yes)
				)
			)
			(property "Dielectric" "template_dielectric"
				(at 13.97 -25.4 0)
				(effects
					(font
						(size 1.27 1.27)
					)
					(justify left bottom)
					(hide yes)
				)
			)
			(property "ki_keywords" "SMT, CAPACITOR, PASSIVE, POLARIZED, TANTALUM"
				(at 0 0 0)
				(effects
					(font
						(size 1.27 1.27)
					)
					(hide yes)
				)
			)
			(symbol "C_Pol_330u_6.3V_KEMET-T520-B_0_1"
				(polyline
					(pts
						(xy 0.9652 1.27) (xy 0.9652 1.778)
					)
					(stroke
						(width 0)
						(type default)
					)
					(fill
						(type none)
					)
				)
				(polyline
					(pts
						(xy 1.2192 1.524) (xy 0.7112 1.524)
					)
					(stroke
						(width 0)
						(type default)
					)
					(fill
						(type none)
					)
				)
				(rectangle
					(start 1.905 -1.524)
					(end 2.286 1.524)
					(stroke
						(width 0)
						(type default)
					)
					(fill
						(type none)
					)
				)
				(rectangle
					(start 2.921 -1.524)
					(end 3.302 1.524)
					(stroke
						(width 0)
						(type default)
					)
					(fill
						(type outline)
					)
				)
			)
			(symbol "C_Pol_330u_6.3V_KEMET-T520-B_1_1"
				(pin passive line
					(at 0 0 0)
					(length 1.8542)
					(name "~"
						(effects
							(font
								(size 1.27 1.27)
							)
						)
					)
					(number "1"
						(effects
							(font
								(size 1.27 1.27)
							)
						)
					)
				)
				(pin passive line
					(at 5.08 0 180)
					(length 1.8542)
					(name "~"
						(effects
							(font
								(size 1.27 1.27)
							)
						)
					)
					(number "2"
						(effects
							(font
								(size 1.27 1.27)
							)
						)
					)
				)
			)
		)
	(symbol "antmicroClockTimingClockGeneratorsPLLsFrequencySynthesizers:SI52112-B6-GT"
			(exclude_from_sim no)
			(in_bom yes)
			(on_board yes)
			(property "Reference" "U"
				(at 38.1 -2.54 0)
				(effects
					(font
						(size 1.27 1.27)
						(thickness 0.15)
					)
					(justify left bottom)
				)
			)
			(property "Value" "SI52112-B6-GT"
				(at 38.1 -5.08 0)
				(effects
					(font
						(size 1.27 1.27)
						(thickness 0.15)
					)
					(justify left bottom)
					(hide yes)
				)
			)
			(property "Footprint" "antmicro-footprints:TSSOP-8_3x4.4mm_P0.65mm"
				(at 38.1 -7.62 0)
				(effects
					(font
						(size 1.27 1.27)
						(thickness 0.15)
					)
					(justify left bottom)
					(hide yes)
				)
			)
			(property "Datasheet" "https://www.skyworksinc.com/-/media/Skyworks/SL/documents/public/data-sheets/Si52112-B5-B6.pdf"
				(at 38.1 -10.16 0)
				(effects
					(font
						(size 1.27 1.27)
						(thickness 0.15)
					)
					(justify left bottom)
					(hide yes)
				)
			)
			(property "Description" "Clock Generator, 100MHz, 2.97V to 3.63V, 2 Outputs, TSSOP-8"
				(at 0 0 0)
				(effects
					(font
						(size 1.27 1.27)
					)
					(hide yes)
				)
			)
			(property "MPN" "SI52112-B6-GT"
				(at 38.1 -12.7 0)
				(effects
					(font
						(size 1.27 1.27)
						(thickness 0.15)
					)
					(justify left bottom)
				)
			)
			(property "Manufacturer" "Skyworks Solutions"
				(at 38.1 -15.24 0)
				(effects
					(font
						(size 1.27 1.27)
						(thickness 0.15)
					)
					(justify left bottom)
					(hide yes)
				)
			)
			(property "Author" "Antmicro"
				(at 38.1 -17.78 0)
				(effects
					(font
						(size 1.27 1.27)
						(thickness 0.15)
					)
					(justify left bottom)
					(hide yes)
				)
			)
			(property "License" "Apache-2.0"
				(at 38.1 -20.32 0)
				(effects
					(font
						(size 1.27 1.27)
						(thickness 0.15)
					)
					(justify left bottom)
					(hide yes)
				)
			)
			(property "ki_keywords" "IC"
				(at 0 0 0)
				(effects
					(font
						(size 1.27 1.27)
					)
					(hide yes)
				)
			)
			(symbol "SI52112-B6-GT_0_1"
				(rectangle
					(start 2.54 2.54)
					(end 21.59 -10.16)
					(stroke
						(width 0.254)
						(type default)
					)
					(fill
						(type background)
					)
				)
			)
			(symbol "SI52112-B6-GT_1_1"
				(pin power_in line
					(at 0 0 0)
					(length 2.54)
					(name "VDD"
						(effects
							(font
								(size 1.27 1.27)
							)
						)
					)
					(number "1"
						(effects
							(font
								(size 1.27 1.27)
							)
						)
					)
				)
				(pin output line
					(at 0 -2.54 0)
					(length 2.54)
					(name "XOUT"
						(effects
							(font
								(size 1.27 1.27)
							)
						)
					)
					(number "2"
						(effects
							(font
								(size 1.27 1.27)
							)
						)
					)
				)
				(pin input line
					(at 0 -5.08 0)
					(length 2.54)
					(name "XIN/CLKIN"
						(effects
							(font
								(size 1.27 1.27)
							)
						)
					)
					(number "3"
						(effects
							(font
								(size 1.27 1.27)
							)
						)
					)
				)
				(pin power_in line
					(at 0 -7.62 0)
					(length 2.54)
					(name "GND"
						(effects
							(font
								(size 1.27 1.27)
							)
						)
					)
					(number "4"
						(effects
							(font
								(size 1.27 1.27)
							)
						)
					)
				)
				(pin output line
					(at 24.13 0 180)
					(length 2.54)
					(name "DIFF1"
						(effects
							(font
								(size 1.27 1.27)
							)
						)
					)
					(number "5"
						(effects
							(font
								(size 1.27 1.27)
							)
						)
					)
				)
				(pin output line
					(at 24.13 -2.54 180)
					(length 2.54)
					(name "~{DIFF1}"
						(effects
							(font
								(size 1.27 1.27)
							)
						)
					)
					(number "6"
						(effects
							(font
								(size 1.27 1.27)
							)
						)
					)
				)
				(pin output line
					(at 24.13 -5.08 180)
					(length 2.54)
					(name "DIFF2"
						(effects
							(font
								(size 1.27 1.27)
							)
						)
					)
					(number "7"
						(effects
							(font
								(size 1.27 1.27)
							)
						)
					)
				)
				(pin output line
					(at 24.13 -7.62 180)
					(length 2.54)
					(name "~{DIFF2}"
						(effects
							(font
								(size 1.27 1.27)
							)
						)
					)
					(number "8"
						(effects
							(font
								(size 1.27 1.27)
							)
						)
					)
				)
			)
		)
	(symbol "antmicroDCDCConverters:LT8350RV"
			(exclude_from_sim no)
			(in_bom yes)
			(on_board yes)
			(property "Reference" "U"
				(at 57.15 -5.08 0)
				(effects
					(font
						(size 1.27 1.27)
						(thickness 0.15)
					)
					(justify left bottom)
				)
			)
			(property "Value" "LT8350RV"
				(at 57.15 -10.16 0)
				(effects
					(font
						(size 1.27 1.27)
						(thickness 0.15)
					)
					(justify left bottom)
					(hide yes)
				)
			)
			(property "Footprint" "antmicro-footprints:QFN-32-4EP_4x6mm_P0.5mm"
				(at 57.15 -12.7 0)
				(effects
					(font
						(size 1.27 1.27)
						(thickness 0.15)
					)
					(justify left bottom)
					(hide yes)
				)
			)
			(property "Datasheet" "https://www.analog.com/media/en/technical-documentation/data-sheets/lt8350.pdf"
				(at 57.15 -15.24 0)
				(effects
					(font
						(size 1.27 1.27)
						(thickness 0.15)
					)
					(justify left bottom)
					(hide yes)
				)
			)
			(property "Description" "DC/DC converter"
				(at 0 0 0)
				(effects
					(font
						(size 1.27 1.27)
					)
					(hide yes)
				)
			)
			(property "MPN" "LT8350RV#PBF"
				(at 57.15 -7.62 0)
				(effects
					(font
						(size 1.27 1.27)
						(thickness 0.15)
					)
					(justify left bottom)
				)
			)
			(property "Manufacturer" "Analog Devices"
				(at 57.15 -17.78 0)
				(effects
					(font
						(size 1.27 1.27)
						(thickness 0.15)
					)
					(justify left bottom)
					(hide yes)
				)
			)
			(property "License" "Apache-2.0"
				(at 57.15 -20.32 0)
				(effects
					(font
						(size 1.27 1.27)
						(thickness 0.15)
					)
					(justify left bottom)
					(hide yes)
				)
			)
			(property "Author" "Antmicro"
				(at 57.15 -22.86 0)
				(effects
					(font
						(size 1.27 1.27)
						(thickness 0.15)
					)
					(justify left bottom)
					(hide yes)
				)
			)
			(property "ki_keywords" "SMT, PMIC, IC, POWER, MANAGEMENT, VOLTAGE, REGULATOR"
				(at 0 0 0)
				(effects
					(font
						(size 1.27 1.27)
					)
					(hide yes)
				)
			)
			(symbol "LT8350RV_1_1"
				(rectangle
					(start 2.54 2.54)
					(end 22.86 -50.8)
					(stroke
						(width 0.254)
						(type default)
					)
					(fill
						(type background)
					)
				)
				(pin output line
					(at 0 -22.86 0)
					(length 2.54)
					(name "ISMON"
						(effects
							(font
								(size 1.27 1.27)
							)
						)
					)
					(number "10"
						(effects
							(font
								(size 1.27 1.27)
							)
						)
					)
				)
				(pin input line
					(at 25.4 -17.78 180)
					(length 2.54)
					(name "ISP"
						(effects
							(font
								(size 1.27 1.27)
							)
						)
					)
					(number "11"
						(effects
							(font
								(size 1.27 1.27)
							)
						)
					)
				)
				(pin input line
					(at 25.4 -20.32 180)
					(length 2.54)
					(name "ISN"
						(effects
							(font
								(size 1.27 1.27)
							)
						)
					)
					(number "12"
						(effects
							(font
								(size 1.27 1.27)
							)
						)
					)
				)
				(pin input line
					(at 0 -33.02 0)
					(length 2.54)
					(name "CTRL"
						(effects
							(font
								(size 1.27 1.27)
							)
						)
					)
					(number "13"
						(effects
							(font
								(size 1.27 1.27)
							)
						)
					)
				)
				(pin input line
					(at 25.4 -15.24 180)
					(length 2.54)
					(name "FB"
						(effects
							(font
								(size 1.27 1.27)
							)
						)
					)
					(number "14"
						(effects
							(font
								(size 1.27 1.27)
							)
						)
					)
				)
				(pin output line
					(at 25.4 -38.1 180)
					(length 2.54)
					(name "VC"
						(effects
							(font
								(size 1.27 1.27)
							)
						)
					)
					(number "15"
						(effects
							(font
								(size 1.27 1.27)
							)
						)
					)
				)
				(pin open_collector line
					(at 0 -15.24 0)
					(length 2.54)
					(name "~{PGOOD}"
						(effects
							(font
								(size 1.27 1.27)
							)
						)
					)
					(number "16"
						(effects
							(font
								(size 1.27 1.27)
							)
						)
					)
				)
				(pin input line
					(at 0 -17.78 0)
					(length 2.54)
					(name "SS"
						(effects
							(font
								(size 1.27 1.27)
							)
						)
					)
					(number "17"
						(effects
							(font
								(size 1.27 1.27)
							)
						)
					)
				)
				(pin input line
					(at 25.4 -40.64 180)
					(length 2.54)
					(name "RT"
						(effects
							(font
								(size 1.27 1.27)
							)
						)
					)
					(number "18"
						(effects
							(font
								(size 1.27 1.27)
							)
						)
					)
				)
				(pin input line
					(at 0 -48.26 0)
					(length 2.54)
					(name "SYNC/MODE"
						(effects
							(font
								(size 1.27 1.27)
							)
						)
					)
					(number "19"
						(effects
							(font
								(size 1.27 1.27)
							)
						)
					)
				)
				(pin power_in line
					(at 0 0 0)
					(length 2.54)
					(name "VIN"
						(effects
							(font
								(size 1.27 1.27)
							)
						)
					)
					(number "2"
						(effects
							(font
								(size 1.27 1.27)
							)
						)
					)
				)
				(pin output line
					(at 0 -27.94 0)
					(length 2.54)
					(name "CLKOUT"
						(effects
							(font
								(size 1.27 1.27)
							)
						)
					)
					(number "20"
						(effects
							(font
								(size 1.27 1.27)
							)
						)
					)
				)
				(pin power_in line
					(at 25.4 -2.54 180)
					(length 2.54)
					(name "EXTVCC"
						(effects
							(font
								(size 1.27 1.27)
							)
						)
					)
					(number "21"
						(effects
							(font
								(size 1.27 1.27)
							)
						)
					)
				)
				(pin output line
					(at 0 -25.4 0)
					(length 2.54)
					(name "LOADTG"
						(effects
							(font
								(size 1.27 1.27)
							)
						)
					)
					(number "22"
						(effects
							(font
								(size 1.27 1.27)
							)
						)
					)
				)
				(pin power_out line
					(at 25.4 0 180)
					(length 2.54)
					(name "VOUT"
						(effects
							(font
								(size 1.27 1.27)
							)
						)
					)
					(number "24"
						(effects
							(font
								(size 1.27 1.27)
							)
						)
					)
				)
				(pin passive line
					(at 25.4 0 180)
					(length 2.54) hide
					(name "VOUT"
						(effects
							(font
								(size 1.27 1.27)
							)
						)
					)
					(number "25"
						(effects
							(font
								(size 1.27 1.27)
							)
						)
					)
				)
				(pin output line
					(at 25.4 -30.48 180)
					(length 2.54)
					(name "SW2"
						(effects
							(font
								(size 1.27 1.27)
							)
						)
					)
					(number "27"
						(effects
							(font
								(size 1.27 1.27)
							)
						)
					)
				)
				(pin passive line
					(at 25.4 -30.48 180)
					(length 2.54) hide
					(name "SW2"
						(effects
							(font
								(size 1.27 1.27)
							)
						)
					)
					(number "28"
						(effects
							(font
								(size 1.27 1.27)
							)
						)
					)
				)
				(pin input line
					(at 25.4 -33.02 180)
					(length 2.54)
					(name "BST2"
						(effects
							(font
								(size 1.27 1.27)
							)
						)
					)
					(number "29"
						(effects
							(font
								(size 1.27 1.27)
							)
						)
					)
				)
				(pin passive line
					(at 0 0 0)
					(length 2.54) hide
					(name "VIN"
						(effects
							(font
								(size 1.27 1.27)
							)
						)
					)
					(number "3"
						(effects
							(font
								(size 1.27 1.27)
							)
						)
					)
				)
				(pin input line
					(at 25.4 -25.4 180)
					(length 2.54)
					(name "BST1"
						(effects
							(font
								(size 1.27 1.27)
							)
						)
					)
					(number "30"
						(effects
							(font
								(size 1.27 1.27)
							)
						)
					)
				)
				(pin output line
					(at 25.4 -27.94 180)
					(length 2.54)
					(name "SW1"
						(effects
							(font
								(size 1.27 1.27)
							)
						)
					)
					(number "31"
						(effects
							(font
								(size 1.27 1.27)
							)
						)
					)
				)
				(pin passive line
					(at 25.4 -27.94 180)
					(length 2.54) hide
					(name "SW1"
						(effects
							(font
								(size 1.27 1.27)
							)
						)
					)
					(number "32"
						(effects
							(font
								(size 1.27 1.27)
							)
						)
					)
				)
				(pin power_in line
					(at 25.4 -48.26 180)
					(length 2.54)
					(name "GND"
						(effects
							(font
								(size 1.27 1.27)
							)
						)
					)
					(number "33"
						(effects
							(font
								(size 1.27 1.27)
							)
						)
					)
				)
				(pin passive line
					(at 25.4 -48.26 180)
					(length 2.54) hide
					(name "GND"
						(effects
							(font
								(size 1.27 1.27)
							)
						)
					)
					(number "34"
						(effects
							(font
								(size 1.27 1.27)
							)
						)
					)
				)
				(pin passive line
					(at 25.4 -48.26 180)
					(length 2.54) hide
					(name "GND"
						(effects
							(font
								(size 1.27 1.27)
							)
						)
					)
					(number "35"
						(effects
							(font
								(size 1.27 1.27)
							)
						)
					)
				)
				(pin passive line
					(at 25.4 -48.26 180)
					(length 2.54) hide
					(name "GND"
						(effects
							(font
								(size 1.27 1.27)
							)
						)
					)
					(number "36"
						(effects
							(font
								(size 1.27 1.27)
							)
						)
					)
				)
				(pin input line
					(at 0 -2.54 0)
					(length 2.54)
					(name "EN/UVLO"
						(effects
							(font
								(size 1.27 1.27)
							)
						)
					)
					(number "5"
						(effects
							(font
								(size 1.27 1.27)
							)
						)
					)
				)
				(pin power_out line
					(at 0 -7.62 0)
					(length 2.54)
					(name "INTVCC"
						(effects
							(font
								(size 1.27 1.27)
							)
						)
					)
					(number "6"
						(effects
							(font
								(size 1.27 1.27)
							)
						)
					)
				)
				(pin unspecified line
					(at 0 -5.08 0)
					(length 2.54)
					(name "RP"
						(effects
							(font
								(size 1.27 1.27)
							)
						)
					)
					(number "7"
						(effects
							(font
								(size 1.27 1.27)
							)
						)
					)
				)
				(pin input line
					(at 0 -35.56 0)
					(length 2.54)
					(name "LOADEN"
						(effects
							(font
								(size 1.27 1.27)
							)
						)
					)
					(number "8"
						(effects
							(font
								(size 1.27 1.27)
							)
						)
					)
				)
				(pin power_out line
					(at 0 -38.1 0)
					(length 2.54)
					(name "VREF"
						(effects
							(font
								(size 1.27 1.27)
							)
						)
					)
					(number "9"
						(effects
							(font
								(size 1.27 1.27)
							)
						)
					)
				)
				(pin passive line
					(at 25.4 -45.72 180)
					(length 2.54)
					(name "MP"
						(effects
							(font
								(size 1.27 1.27)
							)
						)
					)
					(number "MP"
						(effects
							(font
								(size 1.27 1.27)
							)
						)
					)
				)
			)
		)
	(symbol "antmicroDCDCConverters:MP2386GG"
			(exclude_from_sim no)
			(in_bom yes)
			(on_board yes)
			(property "Reference" "U"
				(at 33.02 -5.08 0)
				(effects
					(font
						(size 1.27 1.27)
						(thickness 0.15)
					)
					(justify left bottom)
				)
			)
			(property "Value" "MP2386GG"
				(at 33.02 -7.62 0)
				(effects
					(font
						(size 1.27 1.27)
						(thickness 0.15)
					)
					(justify left bottom)
					(hide yes)
				)
			)
			(property "Footprint" "antmicro-footprints:QFN-11_2x2mm_P0.5mm"
				(at 33.02 -10.16 0)
				(effects
					(font
						(size 1.27 1.27)
						(thickness 0.15)
					)
					(justify left bottom)
					(hide yes)
				)
			)
			(property "Datasheet" "https://www.monolithicpower.com/en/documentview/productdocument/index/version/2/document_type/Datasheet/lang/en/sku/MP2386GG-Z/document_id/4066/"
				(at 33.02 -12.7 0)
				(effects
					(font
						(size 1.27 1.27)
						(thickness 0.15)
					)
					(justify left bottom)
					(hide yes)
				)
			)
			(property "Description" "DC/DC converter"
				(at 0 0 0)
				(effects
					(font
						(size 1.27 1.27)
					)
					(hide yes)
				)
			)
			(property "Manufacturer" "Monolithic Power Systems"
				(at 33.02 -15.24 0)
				(effects
					(font
						(size 1.27 1.27)
						(thickness 0.15)
					)
					(justify left bottom)
					(hide yes)
				)
			)
			(property "MPN" "MP2386GG-P"
				(at 33.02 -17.78 0)
				(effects
					(font
						(size 1.27 1.27)
						(thickness 0.15)
					)
					(justify left bottom)
				)
			)
			(property "Author" "Antmicro"
				(at 33.02 -20.32 0)
				(effects
					(font
						(size 1.27 1.27)
						(thickness 0.15)
					)
					(justify left bottom)
					(hide yes)
				)
			)
			(property "License" "Apache-2.0"
				(at 33.02 -22.86 0)
				(effects
					(font
						(size 1.27 1.27)
						(thickness 0.15)
					)
					(justify left bottom)
					(hide yes)
				)
			)
			(property "ki_keywords" "IC"
				(at 0 0 0)
				(effects
					(font
						(size 1.27 1.27)
					)
					(hide yes)
				)
			)
			(symbol "MP2386GG_1_1"
				(rectangle
					(start 2.54 2.54)
					(end 15.24 -20.32)
					(stroke
						(width 0.254)
						(type default)
					)
					(fill
						(type background)
					)
				)
				(pin power_in line
					(at 0 0 0)
					(length 2.54)
					(name "VIN"
						(effects
							(font
								(size 1.27 1.27)
							)
						)
					)
					(number "1"
						(effects
							(font
								(size 1.27 1.27)
							)
						)
					)
				)
				(pin input line
					(at 17.78 -10.16 180)
					(length 2.54)
					(name "FB"
						(effects
							(font
								(size 1.27 1.27)
							)
						)
					)
					(number "10"
						(effects
							(font
								(size 1.27 1.27)
							)
						)
					)
				)
				(pin input line
					(at 0 -5.08 0)
					(length 2.54)
					(name "EN"
						(effects
							(font
								(size 1.27 1.27)
							)
						)
					)
					(number "11"
						(effects
							(font
								(size 1.27 1.27)
							)
						)
					)
				)
				(pin power_in line
					(at 0 -17.78 0)
					(length 2.54)
					(name "PGND"
						(effects
							(font
								(size 1.27 1.27)
							)
						)
					)
					(number "2"
						(effects
							(font
								(size 1.27 1.27)
							)
						)
					)
				)
				(pin passive line
					(at 0 -17.78 0)
					(length 2.54) hide
					(name "PGND"
						(effects
							(font
								(size 1.27 1.27)
							)
						)
					)
					(number "3"
						(effects
							(font
								(size 1.27 1.27)
							)
						)
					)
				)
				(pin passive line
					(at 0 -17.78 0)
					(length 2.54) hide
					(name "PGND"
						(effects
							(font
								(size 1.27 1.27)
							)
						)
					)
					(number "4"
						(effects
							(font
								(size 1.27 1.27)
							)
						)
					)
				)
				(pin open_collector line
					(at 17.78 -15.24 180)
					(length 2.54)
					(name "PG"
						(effects
							(font
								(size 1.27 1.27)
							)
						)
					)
					(number "5"
						(effects
							(font
								(size 1.27 1.27)
							)
						)
					)
				)
				(pin power_out line
					(at 17.78 -2.54 180)
					(length 2.54)
					(name "SW"
						(effects
							(font
								(size 1.27 1.27)
							)
						)
					)
					(number "6"
						(effects
							(font
								(size 1.27 1.27)
							)
						)
					)
				)
				(pin input line
					(at 17.78 0 180)
					(length 2.54)
					(name "BST"
						(effects
							(font
								(size 1.27 1.27)
							)
						)
					)
					(number "7"
						(effects
							(font
								(size 1.27 1.27)
							)
						)
					)
				)
				(pin power_out line
					(at 0 -7.62 0)
					(length 2.54)
					(name "VCC"
						(effects
							(font
								(size 1.27 1.27)
							)
						)
					)
					(number "8"
						(effects
							(font
								(size 1.27 1.27)
							)
						)
					)
				)
				(pin power_in line
					(at 0 -15.24 0)
					(length 2.54)
					(name "AGND"
						(effects
							(font
								(size 1.27 1.27)
							)
						)
					)
					(number "9"
						(effects
							(font
								(size 1.27 1.27)
							)
						)
					)
				)
			)
		)
	(symbol "antmicroDiodesRectifiersSingle:1N4148WS-7-F"
			(pin_numbers hide)
			(pin_names hide)
			(exclude_from_sim no)
			(in_bom yes)
			(on_board yes)
			(property "Reference" "D"
				(at 21.59 -5.08 0)
				(effects
					(font
						(size 1.27 1.27)
						(thickness 0.15)
					)
					(justify left bottom)
				)
			)
			(property "Value" "1N4148WS-7-F"
				(at 21.59 -10.16 0)
				(effects
					(font
						(size 1.27 1.27)
						(thickness 0.15)
					)
					(justify left bottom)
					(hide yes)
				)
			)
			(property "Footprint" "antmicro-footprints:D_SOD-323"
				(at 21.59 -12.7 0)
				(effects
					(font
						(size 1.27 1.27)
						(thickness 0.15)
					)
					(justify left bottom)
					(hide yes)
				)
			)
			(property "Datasheet" "https://www.diodes.com/assets/Datasheets/ds30097.pdf"
				(at 21.59 -15.24 0)
				(effects
					(font
						(size 1.27 1.27)
						(thickness 0.15)
					)
					(justify left bottom)
					(hide yes)
				)
			)
			(property "Description" "Fast Switching Diode, Single, 75 V, 300 mA, 1.25 V, 4 ns, 2 A"
				(at 0 0 0)
				(effects
					(font
						(size 1.27 1.27)
					)
					(hide yes)
				)
			)
			(property "MPN" "1N4148WS-7-F"
				(at 21.59 -7.62 0)
				(effects
					(font
						(size 1.27 1.27)
						(thickness 0.15)
					)
					(justify left bottom)
				)
			)
			(property "Manufacturer" "Diodes Incorporated"
				(at 21.59 -17.78 0)
				(effects
					(font
						(size 1.27 1.27)
						(thickness 0.15)
					)
					(justify left bottom)
					(hide yes)
				)
			)
			(property "Author" "Antmicro"
				(at 21.59 -20.32 0)
				(effects
					(font
						(size 1.27 1.27)
						(thickness 0.15)
					)
					(justify left bottom)
					(hide yes)
				)
			)
			(property "License" "Apache-2.0"
				(at 21.59 -22.86 0)
				(effects
					(font
						(size 1.27 1.27)
						(thickness 0.15)
					)
					(justify left bottom)
					(hide yes)
				)
			)
			(property "ki_keywords" "SMT, DIODE, SEMICONDUCTOR, SWITCHING"
				(at 0 0 0)
				(effects
					(font
						(size 1.27 1.27)
					)
					(hide yes)
				)
			)
			(symbol "1N4148WS-7-F_0_1"
				(polyline
					(pts
						(xy 1.905 0) (xy 0.635 0)
					)
					(stroke
						(width 0)
						(type default)
					)
					(fill
						(type none)
					)
				)
				(polyline
					(pts
						(xy 4.445 0) (xy 3.175 0)
					)
					(stroke
						(width 0)
						(type default)
					)
					(fill
						(type none)
					)
				)
			)
			(symbol "1N4148WS-7-F_1_1"
				(polyline
					(pts
						(xy 1.778 1.016) (xy 1.778 -1.016)
					)
					(stroke
						(width 0.254)
						(type default)
					)
					(fill
						(type none)
					)
				)
				(polyline
					(pts
						(xy 3.302 1.016) (xy 3.302 -1.016) (xy 1.778 0) (xy 3.302 1.016)
					)
					(stroke
						(width 0.254)
						(type default)
					)
					(fill
						(type outline)
					)
				)
				(pin passive line
					(at 0 0 0)
					(length 0.635)
					(name "C"
						(effects
							(font
								(size 1.27 1.27)
							)
						)
					)
					(number "1"
						(effects
							(font
								(size 1.27 1.27)
							)
						)
					)
				)
				(pin passive line
					(at 5.08 0 180)
					(length 0.635)
					(name "A"
						(effects
							(font
								(size 1.27 1.27)
							)
						)
					)
					(number "2"
						(effects
							(font
								(size 1.27 1.27)
							)
						)
					)
				)
			)
		)
	(symbol "antmicroDiodesZenerSingle:MM3Z3V3C"
			(pin_numbers hide)
			(pin_names hide)
			(exclude_from_sim no)
			(in_bom yes)
			(on_board yes)
			(property "Reference" "D"
				(at 22.86 -5.08 0)
				(effects
					(font
						(size 1.27 1.27)
						(thickness 0.15)
					)
					(justify left bottom)
				)
			)
			(property "Value" "MM3Z3V3C"
				(at 22.86 -15.24 0)
				(effects
					(font
						(size 1.27 1.27)
						(thickness 0.15)
					)
					(justify left bottom)
					(hide yes)
				)
			)
			(property "Footprint" "antmicro-footprints:D_SOD-323F"
				(at 22.86 -10.16 0)
				(effects
					(font
						(size 1.27 1.27)
						(thickness 0.15)
					)
					(justify left bottom)
					(hide yes)
				)
			)
			(property "Datasheet" "https://www.onsemi.com/download/data-sheet/pdf/mm3z9v1c-d.pdf"
				(at 22.86 -12.7 0)
				(effects
					(font
						(size 1.27 1.27)
						(thickness 0.15)
					)
					(justify left bottom)
					(hide yes)
				)
			)
			(property "Description" "Zener Single Diode, 3.3 V, 200 mW, SOD-323F, 2 Pins, 150 °C, Surface Mount"
				(at 0 0 0)
				(effects
					(font
						(size 1.27 1.27)
					)
					(hide yes)
				)
			)
			(property "MPN" "MM3Z3V3C"
				(at 22.86 -7.62 0)
				(effects
					(font
						(size 1.27 1.27)
						(thickness 0.15)
					)
					(justify left bottom)
				)
			)
			(property "Manufacturer" "ON Semiconductor"
				(at 22.86 -17.78 0)
				(effects
					(font
						(size 1.27 1.27)
						(thickness 0.15)
					)
					(justify left bottom)
					(hide yes)
				)
			)
			(property "Author" "Antmicro"
				(at 22.86 -20.32 0)
				(effects
					(font
						(size 1.27 1.27)
						(thickness 0.15)
					)
					(justify left bottom)
					(hide yes)
				)
			)
			(property "License" "Apache-2.0"
				(at 22.86 -22.86 0)
				(effects
					(font
						(size 1.27 1.27)
						(thickness 0.15)
					)
					(justify left bottom)
					(hide yes)
				)
			)
			(property "ki_keywords" "SMT, DIODE, SEMICONDUCTOR, ZENER"
				(at 0 0 0)
				(effects
					(font
						(size 1.27 1.27)
					)
					(hide yes)
				)
			)
			(symbol "MM3Z3V3C_0_1"
				(polyline
					(pts
						(xy 1.905 0) (xy 0.635 0)
					)
					(stroke
						(width 0)
						(type default)
					)
					(fill
						(type none)
					)
				)
				(polyline
					(pts
						(xy 4.445 0) (xy 3.175 0)
					)
					(stroke
						(width 0)
						(type default)
					)
					(fill
						(type none)
					)
				)
			)
			(symbol "MM3Z3V3C_1_1"
				(polyline
					(pts
						(xy 1.778 -1.016) (xy 1.778 1.016)
					)
					(stroke
						(width 0.254)
						(type default)
					)
					(fill
						(type none)
					)
				)
				(polyline
					(pts
						(xy 2.159 1.016) (xy 1.778 1.016)
					)
					(stroke
						(width 0.254)
						(type default)
					)
					(fill
						(type none)
					)
				)
				(polyline
					(pts
						(xy 3.302 -1.016) (xy 3.302 1.016) (xy 1.778 0) (xy 3.302 -1.016)
					)
					(stroke
						(width 0.254)
						(type default)
					)
					(fill
						(type outline)
					)
				)
				(pin passive line
					(at 0 0 0)
					(length 0.635)
					(name "C"
						(effects
							(font
								(size 1.27 1.27)
							)
						)
					)
					(number "1"
						(effects
							(font
								(size 1.27 1.27)
							)
						)
					)
				)
				(pin passive line
					(at 5.08 0 180)
					(length 0.635)
					(name "A"
						(effects
							(font
								(size 1.27 1.27)
							)
						)
					)
					(number "2"
						(effects
							(font
								(size 1.27 1.27)
							)
						)
					)
				)
			)
		)
	(symbol "antmicroEdgeConnectors:PCB-Edge_TE_MULTI-BEAM_2x5_1-2212115-4"
			(exclude_from_sim no)
			(in_bom no)
			(on_board yes)
			(property "Reference" "J"
				(at 19.05 -2.54 0)
				(effects
					(font
						(size 1.27 1.27)
						(thickness 0.15)
					)
					(justify left bottom)
				)
			)
			(property "Value" "PCB-Edge_TE_MULTI-BEAM_2x5_1-2212115-4"
				(at 19.05 -7.62 0)
				(effects
					(font
						(size 1.27 1.27)
						(thickness 0.15)
					)
					(justify left bottom)
					(hide yes)
				)
			)
			(property "Footprint" "antmicro-footprints:PCB-Edge_TE_MULTI-BEAM_2x5_1-2212115-4"
				(at 19.05 -10.16 0)
				(effects
					(font
						(size 1.27 1.27)
						(thickness 0.15)
					)
					(justify left bottom)
					(hide yes)
				)
			)
			(property "Datasheet" "https://www.te.com/usa-en/product-1-2212115-4.datasheet.pdf"
				(at 19.05 -12.7 0)
				(effects
					(font
						(size 1.27 1.27)
						(thickness 0.15)
					)
					(justify left bottom)
					(hide yes)
				)
			)
			(property "Description" "Card Edge Power Connectors, PCB-Edge, 10 Position"
				(at 0 0 0)
				(effects
					(font
						(size 1.27 1.27)
					)
					(hide yes)
				)
			)
			(property "MPN" ""
				(at 19.05 -5.08 0)
				(effects
					(font
						(size 1.27 1.27)
						(thickness 0.15)
					)
					(justify left bottom)
				)
			)
			(property "Manufacturer" ""
				(at 19.05 -15.24 0)
				(effects
					(font
						(size 1.27 1.27)
						(thickness 0.15)
					)
					(justify left bottom)
					(hide yes)
				)
			)
			(property "Author" "Antmicro"
				(at 19.05 -17.78 0)
				(effects
					(font
						(size 1.27 1.27)
						(thickness 0.15)
					)
					(justify left bottom)
					(hide yes)
				)
			)
			(property "License" "Apache-2.0"
				(at 19.05 -20.32 0)
				(effects
					(font
						(size 1.27 1.27)
						(thickness 0.15)
					)
					(justify left bottom)
					(hide yes)
				)
			)
			(property "ki_keywords" "EDGE,  CONNECTOR"
				(at 0 0 0)
				(effects
					(font
						(size 1.27 1.27)
					)
					(hide yes)
				)
			)
			(symbol "PCB-Edge_TE_MULTI-BEAM_2x5_1-2212115-4_1_1"
				(rectangle
					(start 2.54 2.54)
					(end 10.16 -25.4)
					(stroke
						(width 0.254)
						(type default)
					)
					(fill
						(type background)
					)
				)
				(pin power_in line
					(at 0 0 0)
					(length 2.54)
					(name "P1"
						(effects
							(font
								(size 1.27 1.27)
							)
						)
					)
					(number "1"
						(effects
							(font
								(size 1.27 1.27)
							)
						)
					)
				)
				(pin passive line
					(at 0 -22.86 0)
					(length 2.54)
					(name "S8"
						(effects
							(font
								(size 1.27 1.27)
							)
						)
					)
					(number "10"
						(effects
							(font
								(size 1.27 1.27)
							)
						)
					)
				)
				(pin power_in line
					(at 0 -2.54 0)
					(length 2.54)
					(name "P2"
						(effects
							(font
								(size 1.27 1.27)
							)
						)
					)
					(number "2"
						(effects
							(font
								(size 1.27 1.27)
							)
						)
					)
				)
				(pin passive line
					(at 0 -5.08 0)
					(length 2.54)
					(name "S1"
						(effects
							(font
								(size 1.27 1.27)
							)
						)
					)
					(number "3"
						(effects
							(font
								(size 1.27 1.27)
							)
						)
					)
				)
				(pin passive line
					(at 0 -7.62 0)
					(length 2.54)
					(name "S2"
						(effects
							(font
								(size 1.27 1.27)
							)
						)
					)
					(number "4"
						(effects
							(font
								(size 1.27 1.27)
							)
						)
					)
				)
				(pin passive line
					(at 0 -10.16 0)
					(length 2.54)
					(name "S3"
						(effects
							(font
								(size 1.27 1.27)
							)
						)
					)
					(number "5"
						(effects
							(font
								(size 1.27 1.27)
							)
						)
					)
				)
				(pin passive line
					(at 0 -12.7 0)
					(length 2.54)
					(name "S4"
						(effects
							(font
								(size 1.27 1.27)
							)
						)
					)
					(number "6"
						(effects
							(font
								(size 1.27 1.27)
							)
						)
					)
				)
				(pin passive line
					(at 0 -15.24 0)
					(length 2.54)
					(name "S5"
						(effects
							(font
								(size 1.27 1.27)
							)
						)
					)
					(number "7"
						(effects
							(font
								(size 1.27 1.27)
							)
						)
					)
				)
				(pin passive line
					(at 0 -17.78 0)
					(length 2.54)
					(name "S6"
						(effects
							(font
								(size 1.27 1.27)
							)
						)
					)
					(number "8"
						(effects
							(font
								(size 1.27 1.27)
							)
						)
					)
				)
				(pin passive line
					(at 0 -20.32 0)
					(length 2.54)
					(name "S7"
						(effects
							(font
								(size 1.27 1.27)
							)
						)
					)
					(number "9"
						(effects
							(font
								(size 1.27 1.27)
							)
						)
					)
				)
			)
		)
	(symbol "antmicroFerriteBeadsandChips:FB_120Z_3A_Murata-BLM18SG_0603"
			(pin_numbers hide)
			(pin_names hide)
			(exclude_from_sim no)
			(in_bom yes)
			(on_board yes)
			(property "Reference" "FB"
				(at 13.97 0 0)
				(effects
					(font
						(size 1.27 1.27)
						(thickness 0.15)
					)
					(justify left bottom)
				)
			)
			(property "Value" "FB_120Z_3A_Murata-BLM18SG_0603"
				(at 13.97 -2.54 0)
				(effects
					(font
						(size 1.27 1.27)
						(thickness 0.15)
					)
					(justify left bottom)
					(hide yes)
				)
			)
			(property "Footprint" "antmicro-footprints:FB_0603_1608Metric"
				(at 13.97 -7.62 0)
				(effects
					(font
						(size 1.27 1.27)
						(thickness 0.15)
					)
					(justify left bottom)
					(hide yes)
				)
			)
			(property "Datasheet" "https://www.murata.com/products/productdata/8796738650142/ENFA0003.pdf?1681308024000"
				(at 13.97 -10.16 0)
				(effects
					(font
						(size 1.27 1.27)
						(thickness 0.15)
					)
					(justify left bottom)
					(hide yes)
				)
			)
			(property "Description" "Ferrite Bead, 0603 [1608 Metric], 120 ohm, 3 A, BLM18S, 0.025 ohm, ± 25%, DC power line (thin type) "
				(at 0 0 0)
				(effects
					(font
						(size 1.27 1.27)
					)
					(hide yes)
				)
			)
			(property "Val" "120Z/3A"
				(at 13.97 -5.08 0)
				(effects
					(font
						(size 1.27 1.27)
					)
					(justify left bottom)
				)
			)
			(property "MPN" "BLM18SG121TN1D"
				(at 13.97 -12.7 0)
				(effects
					(font
						(size 1.27 1.27)
						(thickness 0.15)
					)
					(justify left bottom)
					(hide yes)
				)
			)
			(property "Manufacturer" "Murata"
				(at 13.97 -15.24 0)
				(effects
					(font
						(size 1.27 1.27)
						(thickness 0.15)
					)
					(justify left bottom)
					(hide yes)
				)
			)
			(property "Current" ""
				(at 20.32 -22.86 0)
				(effects
					(font
						(size 1.27 1.27)
						(thickness 0.15)
					)
					(justify left bottom)
					(hide yes)
				)
			)
			(property "Author" "Antmicro"
				(at 13.97 -17.78 0)
				(effects
					(font
						(size 1.27 1.27)
						(thickness 0.15)
					)
					(justify left bottom)
					(hide yes)
				)
			)
			(property "License" "Apache-2.0"
				(at 13.97 -20.32 0)
				(effects
					(font
						(size 1.27 1.27)
						(thickness 0.15)
					)
					(justify left bottom)
					(hide yes)
				)
			)
			(property "ki_keywords" "0603, SMT, FERRITE BEAD, PASSIVE"
				(at 0 0 0)
				(effects
					(font
						(size 1.27 1.27)
					)
					(hide yes)
				)
			)
			(symbol "FB_120Z_3A_Murata-BLM18SG_0603_0_1"
				(polyline
					(pts
						(xy 1.651 0) (xy 1.2446 0)
					)
					(stroke
						(width 0)
						(type default)
					)
					(fill
						(type none)
					)
				)
				(polyline
					(pts
						(xy 3.81 0) (xy 3.3274 0)
					)
					(stroke
						(width 0)
						(type default)
					)
					(fill
						(type none)
					)
				)
				(polyline
					(pts
						(xy 2.2606 -1.8288) (xy 1.0414 -1.1176) (xy 2.7432 1.8288) (xy 3.9624 1.1176) (xy 2.2606 -1.8288)
					)
					(stroke
						(width 0)
						(type default)
					)
					(fill
						(type none)
					)
				)
			)
			(symbol "FB_120Z_3A_Murata-BLM18SG_0603_1_1"
				(pin passive line
					(at 0 0 0)
					(length 1.27)
					(name "~"
						(effects
							(font
								(size 1.27 1.27)
							)
						)
					)
					(number "1"
						(effects
							(font
								(size 1.27 1.27)
							)
						)
					)
				)
				(pin passive line
					(at 5.08 0 180)
					(length 1.27)
					(name "~"
						(effects
							(font
								(size 1.27 1.27)
							)
						)
					)
					(number "2"
						(effects
							(font
								(size 1.27 1.27)
							)
						)
					)
				)
			)
		)
	(symbol "antmicroFerriteBeadsandChips:FB_30Z_8.5A_Murata-BLM21SN_0805"
			(pin_numbers hide)
			(pin_names hide)
			(exclude_from_sim no)
			(in_bom yes)
			(on_board yes)
			(property "Reference" "FB"
				(at 13.97 0 0)
				(effects
					(font
						(size 1.27 1.27)
						(thickness 0.15)
					)
					(justify left bottom)
				)
			)
			(property "Value" "FB_30Z_8.5A_Murata-BLM21SN_0805"
				(at 13.97 -2.54 0)
				(effects
					(font
						(size 1.27 1.27)
						(thickness 0.15)
					)
					(justify left bottom)
					(hide yes)
				)
			)
			(property "Footprint" "antmicro-footprints:FB_0805_2012Metric"
				(at 13.97 -7.62 0)
				(effects
					(font
						(size 1.27 1.27)
						(thickness 0.15)
					)
					(justify left bottom)
					(hide yes)
				)
			)
			(property "Datasheet" "https://www.murata.com/en-sg/products/productdata/8796738977822/ENFA0005.pdf?1519270210000"
				(at 13.97 -10.16 0)
				(effects
					(font
						(size 1.27 1.27)
						(thickness 0.15)
					)
					(justify left bottom)
					(hide yes)
				)
			)
			(property "Description" "Ferrite Bead, 0805 [2012 Metric], 30 ohm, 8.5 A, BLM21SN, 0.004 ohm, ± 10ohm, DC power line"
				(at 0 0 0)
				(effects
					(font
						(size 1.27 1.27)
					)
					(hide yes)
				)
			)
			(property "Val" "30Z/8.5A"
				(at 13.97 -5.08 0)
				(effects
					(font
						(size 1.27 1.27)
					)
					(justify left bottom)
				)
			)
			(property "MPN" "BLM21SN300SZ1D"
				(at 13.97 -12.7 0)
				(effects
					(font
						(size 1.27 1.27)
						(thickness 0.15)
					)
					(justify left bottom)
					(hide yes)
				)
			)
			(property "Manufacturer" "Murata"
				(at 13.97 -15.24 0)
				(effects
					(font
						(size 1.27 1.27)
						(thickness 0.15)
					)
					(justify left bottom)
					(hide yes)
				)
			)
			(property "Current" ""
				(at 20.32 -22.86 0)
				(effects
					(font
						(size 1.27 1.27)
						(thickness 0.15)
					)
					(justify left bottom)
					(hide yes)
				)
			)
			(property "Author" "Antmicro"
				(at 13.97 -17.78 0)
				(effects
					(font
						(size 1.27 1.27)
						(thickness 0.15)
					)
					(justify left bottom)
					(hide yes)
				)
			)
			(property "License" "Apache-2.0"
				(at 13.97 -20.32 0)
				(effects
					(font
						(size 1.27 1.27)
						(thickness 0.15)
					)
					(justify left bottom)
					(hide yes)
				)
			)
			(property "ki_keywords" "0805, SMT, FERRITE BEAD, PASSIVE"
				(at 0 0 0)
				(effects
					(font
						(size 1.27 1.27)
					)
					(hide yes)
				)
			)
			(symbol "FB_30Z_8.5A_Murata-BLM21SN_0805_0_1"
				(polyline
					(pts
						(xy 1.651 0) (xy 1.2446 0)
					)
					(stroke
						(width 0)
						(type default)
					)
					(fill
						(type none)
					)
				)
				(polyline
					(pts
						(xy 3.81 0) (xy 3.3274 0)
					)
					(stroke
						(width 0)
						(type default)
					)
					(fill
						(type none)
					)
				)
				(polyline
					(pts
						(xy 2.2606 -1.8288) (xy 1.0414 -1.1176) (xy 2.7432 1.8288) (xy 3.9624 1.1176) (xy 2.2606 -1.8288)
					)
					(stroke
						(width 0)
						(type default)
					)
					(fill
						(type none)
					)
				)
			)
			(symbol "FB_30Z_8.5A_Murata-BLM21SN_0805_1_1"
				(pin passive line
					(at 0 0 0)
					(length 1.27)
					(name "~"
						(effects
							(font
								(size 1.27 1.27)
							)
						)
					)
					(number "1"
						(effects
							(font
								(size 1.27 1.27)
							)
						)
					)
				)
				(pin passive line
					(at 5.08 0 180)
					(length 1.27)
					(name "~"
						(effects
							(font
								(size 1.27 1.27)
							)
						)
					)
					(number "2"
						(effects
							(font
								(size 1.27 1.27)
							)
						)
					)
				)
			)
		)
	(symbol "antmicroFiducialMarks:Fiducial_1mm_Mask3mm"
			(exclude_from_sim no)
			(in_bom no)
			(on_board yes)
			(property "Reference" "FD"
				(at 7.62 0 0)
				(effects
					(font
						(size 1.27 1.27)
						(thickness 0.15)
					)
					(justify left bottom)
				)
			)
			(property "Value" "Fiducial_1mm_Mask3mm"
				(at 7.62 -2.54 0)
				(effects
					(font
						(size 1.27 1.27)
						(thickness 0.15)
					)
					(justify left bottom)
				)
			)
			(property "Footprint" "antmicro-footprints:Fiducial_1mm_Mask3mm"
				(at 7.62 -5.08 0)
				(effects
					(font
						(size 1.27 1.27)
						(thickness 0.15)
					)
					(justify left bottom)
					(hide yes)
				)
			)
			(property "Datasheet" ""
				(at 7.315 -9.22 0)
				(effects
					(font
						(size 1.27 1.27)
						(thickness 0.15)
					)
					(justify left bottom)
					(hide yes)
				)
			)
			(property "Description" "Fiducial mask"
				(at 0 0 0)
				(effects
					(font
						(size 1.27 1.27)
					)
					(hide yes)
				)
			)
			(property "Author" "Antmicro"
				(at 7.62 -7.62 0)
				(effects
					(font
						(size 1.27 1.27)
						(thickness 0.15)
					)
					(justify left bottom)
					(hide yes)
				)
			)
			(property "License" "Apache-2.0"
				(at 7.62 -10.16 0)
				(effects
					(font
						(size 1.27 1.27)
						(thickness 0.15)
					)
					(justify left bottom)
					(hide yes)
				)
			)
			(symbol "Fiducial_1mm_Mask3mm_1_1"
				(circle
					(center 0 0)
					(radius 3.1623)
					(stroke
						(width 0.254)
						(type default)
					)
					(fill
						(type background)
					)
				)
			)
		)
	(symbol "antmicroFixedInductors:L_1u_1.8A_0603"
			(pin_numbers hide)
			(pin_names hide)
			(exclude_from_sim no)
			(in_bom yes)
			(on_board yes)
			(property "Reference" "L"
				(at 13.97 0 0)
				(effects
					(font
						(size 1.27 1.27)
						(thickness 0.15)
					)
					(justify left bottom)
				)
			)
			(property "Value" "L_1u_1.8A_0603"
				(at 13.97 -2.54 0)
				(effects
					(font
						(size 1.27 1.27)
						(thickness 0.15)
					)
					(justify left bottom)
					(hide yes)
				)
			)
			(property "Footprint" "antmicro-footprints:L_0603_1608Metric"
				(at 13.97 -7.62 0)
				(effects
					(font
						(size 1.27 1.27)
						(thickness 0.15)
					)
					(justify left bottom)
					(hide yes)
				)
			)
			(property "Datasheet" "https://search.murata.co.jp/Ceramy/image/img/P02/JETE243A-0041.pdf"
				(at 13.97 -10.16 0)
				(effects
					(font
						(size 1.27 1.27)
						(thickness 0.15)
					)
					(justify left bottom)
					(hide yes)
				)
			)
			(property "Description" "Power Inductor (SMT), 1 µH, 1.8 A, Shielded, 1.9 A, DFE Series, 0603 [1608 Metric]"
				(at 0 0 0)
				(effects
					(font
						(size 1.27 1.27)
					)
					(hide yes)
				)
			)
			(property "Val" "1u/1.8A"
				(at 13.97 -5.08 0)
				(effects
					(font
						(size 1.27 1.27)
						(thickness 0.15)
					)
					(justify left bottom)
				)
			)
			(property "Manufacturer" "Murata"
				(at 13.97 -12.7 0)
				(effects
					(font
						(size 1.27 1.27)
						(thickness 0.15)
					)
					(justify left bottom)
					(hide yes)
				)
			)
			(property "MPN" "DFE18SBN1R0ME0L"
				(at 13.97 -15.24 0)
				(effects
					(font
						(size 1.27 1.27)
						(thickness 0.15)
					)
					(justify left bottom)
					(hide yes)
				)
			)
			(property "ISat" "1.9A"
				(at 13.97 -17.78 0)
				(effects
					(font
						(size 1.27 1.27)
					)
					(justify left bottom)
					(hide yes)
				)
			)
			(property "IMax" "1.8A"
				(at 13.97 -20.32 0)
				(effects
					(font
						(size 1.27 1.27)
						(thickness 0.15)
					)
					(justify left bottom)
					(hide yes)
				)
			)
			(property "Size" "1.6x0.8"
				(at 13.97 -22.86 0)
				(effects
					(font
						(size 1.27 1.27)
						(thickness 0.15)
					)
					(justify left bottom)
					(hide yes)
				)
			)
			(property "Author" "Antmicro"
				(at 13.97 -25.4 0)
				(effects
					(font
						(size 1.27 1.27)
						(thickness 0.15)
					)
					(justify left bottom)
					(hide yes)
				)
			)
			(property "License" "Apache-2.0"
				(at 13.97 -27.94 0)
				(effects
					(font
						(size 1.27 1.27)
						(thickness 0.15)
					)
					(justify left bottom)
					(hide yes)
				)
			)
			(property "ki_keywords" "INDUCTOR, PASSIVE"
				(at 0 0 0)
				(effects
					(font
						(size 1.27 1.27)
					)
					(hide yes)
				)
			)
			(symbol "L_1u_1.8A_0603_0_1"
				(arc
					(start 1.524 0)
					(mid 1.016 0.5058)
					(end 0.508 0)
					(stroke
						(width 0)
						(type default)
					)
					(fill
						(type none)
					)
				)
				(arc
					(start 2.54 0)
					(mid 2.032 0.5058)
					(end 1.524 0)
					(stroke
						(width 0)
						(type default)
					)
					(fill
						(type none)
					)
				)
				(arc
					(start 3.556 0)
					(mid 3.048 0.5058)
					(end 2.54 0)
					(stroke
						(width 0)
						(type default)
					)
					(fill
						(type none)
					)
				)
				(arc
					(start 4.572 0)
					(mid 4.064 0.5058)
					(end 3.556 0)
					(stroke
						(width 0)
						(type default)
					)
					(fill
						(type none)
					)
				)
			)
			(symbol "L_1u_1.8A_0603_1_1"
				(pin passive line
					(at 0 0 0)
					(length 0.508)
					(name "~"
						(effects
							(font
								(size 1.27 1.27)
							)
						)
					)
					(number "1"
						(effects
							(font
								(size 1.27 1.27)
							)
						)
					)
				)
				(pin passive line
					(at 5.08 0 180)
					(length 0.508)
					(name "~"
						(effects
							(font
								(size 1.27 1.27)
							)
						)
					)
					(number "2"
						(effects
							(font
								(size 1.27 1.27)
							)
						)
					)
				)
			)
		)
	(symbol "antmicroFixedInductors:L_2u2_9.7A_Coilcraft-XAL5030"
			(pin_numbers hide)
			(pin_names hide)
			(exclude_from_sim no)
			(in_bom yes)
			(on_board yes)
			(property "Reference" "L"
				(at 13.97 0 0)
				(effects
					(font
						(size 1.27 1.27)
						(thickness 0.15)
					)
					(justify left bottom)
				)
			)
			(property "Value" "L_2u2_9.7A_Coilcraft-XAL5030"
				(at 13.97 -2.54 0)
				(effects
					(font
						(size 1.27 1.27)
						(thickness 0.15)
					)
					(justify left bottom)
					(hide yes)
				)
			)
			(property "Footprint" "antmicro-footprints:L_Coilcraft-XAL5030"
				(at 13.97 -7.62 0)
				(effects
					(font
						(size 1.27 1.27)
						(thickness 0.15)
					)
					(justify left bottom)
					(hide yes)
				)
			)
			(property "Datasheet" "https://www.coilcraft.com/getmedia/49bc46c8-4b2c-45b9-9b6c-2eaa235ea698/xal50xx.pdf"
				(at 13.97 -10.16 0)
				(effects
					(font
						(size 1.27 1.27)
						(thickness 0.15)
					)
					(justify left bottom)
					(hide yes)
				)
			)
			(property "Description" "Power Inductor (SMT), 2.2 µH, 9.7 A, Shielded, 9.2 A, XAL5030"
				(at 0 0 0)
				(effects
					(font
						(size 1.27 1.27)
					)
					(hide yes)
				)
			)
			(property "Val" "2u2/9.7A"
				(at 13.97 -5.08 0)
				(effects
					(font
						(size 1.27 1.27)
						(thickness 0.15)
					)
					(justify left bottom)
				)
			)
			(property "Manufacturer" "Coilcraft"
				(at 13.97 -12.7 0)
				(effects
					(font
						(size 1.27 1.27)
						(thickness 0.15)
					)
					(justify left bottom)
					(hide yes)
				)
			)
			(property "MPN" "XAL5030-222MEC"
				(at 13.97 -15.24 0)
				(effects
					(font
						(size 1.27 1.27)
						(thickness 0.15)
					)
					(justify left bottom)
					(hide yes)
				)
			)
			(property "ISat" "9.2 A"
				(at 13.97 -16.51 0)
				(effects
					(font
						(size 1.27 1.27)
					)
					(justify left)
					(hide yes)
				)
			)
			(property "IMax" "9.7 A"
				(at 13.97 -20.32 0)
				(effects
					(font
						(size 1.27 1.27)
						(thickness 0.15)
					)
					(justify left bottom)
					(hide yes)
				)
			)
			(property "Size" "5.28x5.48"
				(at 13.97 -22.86 0)
				(effects
					(font
						(size 1.27 1.27)
						(thickness 0.15)
					)
					(justify left bottom)
					(hide yes)
				)
			)
			(property "Author" "Antmicro"
				(at 13.97 -25.4 0)
				(effects
					(font
						(size 1.27 1.27)
						(thickness 0.15)
					)
					(justify left bottom)
					(hide yes)
				)
			)
			(property "License" "Apache-2.0"
				(at 13.97 -27.94 0)
				(effects
					(font
						(size 1.27 1.27)
						(thickness 0.15)
					)
					(justify left bottom)
					(hide yes)
				)
			)
			(property "ki_keywords" "SMT, INDUCTOR, PASSIVE"
				(at 0 0 0)
				(effects
					(font
						(size 1.27 1.27)
					)
					(hide yes)
				)
			)
			(symbol "L_2u2_9.7A_Coilcraft-XAL5030_0_1"
				(arc
					(start 1.524 0)
					(mid 1.016 0.5058)
					(end 0.508 0)
					(stroke
						(width 0)
						(type default)
					)
					(fill
						(type none)
					)
				)
				(arc
					(start 2.54 0)
					(mid 2.032 0.5058)
					(end 1.524 0)
					(stroke
						(width 0)
						(type default)
					)
					(fill
						(type none)
					)
				)
				(arc
					(start 3.556 0)
					(mid 3.048 0.5058)
					(end 2.54 0)
					(stroke
						(width 0)
						(type default)
					)
					(fill
						(type none)
					)
				)
				(arc
					(start 4.572 0)
					(mid 4.064 0.5058)
					(end 3.556 0)
					(stroke
						(width 0)
						(type default)
					)
					(fill
						(type none)
					)
				)
			)
			(symbol "L_2u2_9.7A_Coilcraft-XAL5030_1_1"
				(pin passive line
					(at 0 0 0)
					(length 0.508)
					(name "~"
						(effects
							(font
								(size 1.27 1.27)
							)
						)
					)
					(number "1"
						(effects
							(font
								(size 1.27 1.27)
							)
						)
					)
				)
				(pin passive line
					(at 5.08 0 180)
					(length 0.508)
					(name "~"
						(effects
							(font
								(size 1.27 1.27)
							)
						)
					)
					(number "2"
						(effects
							(font
								(size 1.27 1.27)
							)
						)
					)
				)
			)
		)
	(symbol "antmicroFixedInductors:L_680n_7.6A_IHLP1616BZ"
			(pin_numbers hide)
			(pin_names hide)
			(exclude_from_sim no)
			(in_bom yes)
			(on_board yes)
			(property "Reference" "L"
				(at 13.97 0 0)
				(effects
					(font
						(size 1.27 1.27)
						(thickness 0.15)
					)
					(justify left bottom)
				)
			)
			(property "Value" "L_680n_7.6A_IHLP1616BZ"
				(at 13.97 -2.54 0)
				(effects
					(font
						(size 1.27 1.27)
						(thickness 0.15)
					)
					(justify left bottom)
					(hide yes)
				)
			)
			(property "Footprint" "antmicro-footprints:L_Vishay-IHLP1616BZ"
				(at 13.97 -7.62 0)
				(effects
					(font
						(size 1.27 1.27)
						(thickness 0.15)
					)
					(justify left bottom)
					(hide yes)
				)
			)
			(property "Datasheet" "https://www.mouser.com/datasheet/2/427/ihlp1616bz5a-1763007.pdf"
				(at 13.97 -10.16 0)
				(effects
					(font
						(size 1.27 1.27)
						(thickness 0.15)
					)
					(justify left bottom)
					(hide yes)
				)
			)
			(property "Description" "Power Inductor (SMT), 680 nH, 7.6 A, Shielded, 6.8 A, IHLP-1616BZ-5A"
				(at 0 0 0)
				(effects
					(font
						(size 1.27 1.27)
					)
					(hide yes)
				)
			)
			(property "Val" "680n/7.6A"
				(at 13.97 -5.08 0)
				(effects
					(font
						(size 1.27 1.27)
						(thickness 0.15)
					)
					(justify left bottom)
				)
			)
			(property "Manufacturer" "Vishay"
				(at 13.97 -12.7 0)
				(effects
					(font
						(size 1.27 1.27)
						(thickness 0.15)
					)
					(justify left bottom)
					(hide yes)
				)
			)
			(property "MPN" "IHLP1616BZERR68M5A"
				(at 13.97 -15.24 0)
				(effects
					(font
						(size 1.27 1.27)
						(thickness 0.15)
					)
					(justify left bottom)
					(hide yes)
				)
			)
			(property "ISat" "6.8 A"
				(at 13.97 -16.51 0)
				(effects
					(font
						(size 1.27 1.27)
					)
					(justify left)
					(hide yes)
				)
			)
			(property "IMax" "7.6 A"
				(at 13.97 -20.32 0)
				(effects
					(font
						(size 1.27 1.27)
						(thickness 0.15)
					)
					(justify left bottom)
					(hide yes)
				)
			)
			(property "Size" "4.06x4.06"
				(at 13.97 -22.86 0)
				(effects
					(font
						(size 1.27 1.27)
						(thickness 0.15)
					)
					(justify left bottom)
					(hide yes)
				)
			)
			(property "Author" "Antmicro"
				(at 13.97 -25.4 0)
				(effects
					(font
						(size 1.27 1.27)
						(thickness 0.15)
					)
					(justify left bottom)
					(hide yes)
				)
			)
			(property "License" "Apache-2.0"
				(at 13.97 -27.94 0)
				(effects
					(font
						(size 1.27 1.27)
						(thickness 0.15)
					)
					(justify left bottom)
					(hide yes)
				)
			)
			(property "ki_keywords" "SMT, INDUCTOR, PASSIVE"
				(at 0 0 0)
				(effects
					(font
						(size 1.27 1.27)
					)
					(hide yes)
				)
			)
			(symbol "L_680n_7.6A_IHLP1616BZ_0_1"
				(arc
					(start 1.524 0)
					(mid 1.016 0.5058)
					(end 0.508 0)
					(stroke
						(width 0)
						(type default)
					)
					(fill
						(type none)
					)
				)
				(arc
					(start 2.54 0)
					(mid 2.032 0.5058)
					(end 1.524 0)
					(stroke
						(width 0)
						(type default)
					)
					(fill
						(type none)
					)
				)
				(arc
					(start 3.556 0)
					(mid 3.048 0.5058)
					(end 2.54 0)
					(stroke
						(width 0)
						(type default)
					)
					(fill
						(type none)
					)
				)
				(arc
					(start 4.572 0)
					(mid 4.064 0.5058)
					(end 3.556 0)
					(stroke
						(width 0)
						(type default)
					)
					(fill
						(type none)
					)
				)
			)
			(symbol "L_680n_7.6A_IHLP1616BZ_1_1"
				(pin passive line
					(at 0 0 0)
					(length 0.508)
					(name "~"
						(effects
							(font
								(size 1.27 1.27)
							)
						)
					)
					(number "1"
						(effects
							(font
								(size 1.27 1.27)
							)
						)
					)
				)
				(pin passive line
					(at 5.08 0 180)
					(length 0.508)
					(name "~"
						(effects
							(font
								(size 1.27 1.27)
							)
						)
					)
					(number "2"
						(effects
							(font
								(size 1.27 1.27)
							)
						)
					)
				)
			)
		)
	(symbol "antmicroFixedInductors:L_6u8_12.8A_Coilcraft-XAL7070"
			(pin_numbers hide)
			(pin_names hide)
			(exclude_from_sim no)
			(in_bom yes)
			(on_board yes)
			(property "Reference" "L"
				(at 13.97 0 0)
				(effects
					(font
						(size 1.27 1.27)
						(thickness 0.15)
					)
					(justify left bottom)
				)
			)
			(property "Value" "L_6u8_12.8A_Coilcraft-XAL7070"
				(at 13.97 -2.54 0)
				(effects
					(font
						(size 1.27 1.27)
						(thickness 0.15)
					)
					(justify left bottom)
					(hide yes)
				)
			)
			(property "Footprint" "antmicro-footprints:L_Coilcraft-XAL7070"
				(at 13.97 -7.62 0)
				(effects
					(font
						(size 1.27 1.27)
						(thickness 0.15)
					)
					(justify left bottom)
					(hide yes)
				)
			)
			(property "Datasheet" "https://www.coilcraft.com/en-us/products/power/shielded-inductors/molded-inductor/xal/xal7070/xal7070-682"
				(at 13.97 -10.16 0)
				(effects
					(font
						(size 1.27 1.27)
						(thickness 0.15)
					)
					(justify left bottom)
					(hide yes)
				)
			)
			(property "Description" "Power Inductor (SMT), 6.8 µH, 9.2 A, Shielded, 12.8 A, XAL7070"
				(at 0 0 0)
				(effects
					(font
						(size 1.27 1.27)
					)
					(hide yes)
				)
			)
			(property "Val" "6u8/12.8A"
				(at 13.97 -5.08 0)
				(effects
					(font
						(size 1.27 1.27)
						(thickness 0.15)
					)
					(justify left bottom)
				)
			)
			(property "Manufacturer" "Coilcraft"
				(at 13.97 -12.7 0)
				(effects
					(font
						(size 1.27 1.27)
						(thickness 0.15)
					)
					(justify left bottom)
					(hide yes)
				)
			)
			(property "MPN" "XAL7070-682MEC"
				(at 13.97 -15.24 0)
				(effects
					(font
						(size 1.27 1.27)
						(thickness 0.15)
					)
					(justify left bottom)
					(hide yes)
				)
			)
			(property "ISat" "12.8 A"
				(at 13.97 -16.51 0)
				(effects
					(font
						(size 1.27 1.27)
					)
					(justify left)
					(hide yes)
				)
			)
			(property "IMax" "9.2 A"
				(at 13.97 -20.32 0)
				(effects
					(font
						(size 1.27 1.27)
						(thickness 0.15)
					)
					(justify left bottom)
					(hide yes)
				)
			)
			(property "Size" "7.7x8"
				(at 13.97 -22.86 0)
				(effects
					(font
						(size 1.27 1.27)
						(thickness 0.15)
					)
					(justify left bottom)
					(hide yes)
				)
			)
			(property "Author" "Antmicro"
				(at 13.97 -25.4 0)
				(effects
					(font
						(size 1.27 1.27)
						(thickness 0.15)
					)
					(justify left bottom)
					(hide yes)
				)
			)
			(property "License" "Apache-2.0"
				(at 13.97 -27.94 0)
				(effects
					(font
						(size 1.27 1.27)
						(thickness 0.15)
					)
					(justify left bottom)
					(hide yes)
				)
			)
			(property "ki_keywords" "SMT, INDUCTOR, PASSIVE"
				(at 0 0 0)
				(effects
					(font
						(size 1.27 1.27)
					)
					(hide yes)
				)
			)
			(symbol "L_6u8_12.8A_Coilcraft-XAL7070_0_1"
				(arc
					(start 1.524 0)
					(mid 1.016 0.5058)
					(end 0.508 0)
					(stroke
						(width 0)
						(type default)
					)
					(fill
						(type none)
					)
				)
				(arc
					(start 2.54 0)
					(mid 2.032 0.5058)
					(end 1.524 0)
					(stroke
						(width 0)
						(type default)
					)
					(fill
						(type none)
					)
				)
				(arc
					(start 3.556 0)
					(mid 3.048 0.5058)
					(end 2.54 0)
					(stroke
						(width 0)
						(type default)
					)
					(fill
						(type none)
					)
				)
				(arc
					(start 4.572 0)
					(mid 4.064 0.5058)
					(end 3.556 0)
					(stroke
						(width 0)
						(type default)
					)
					(fill
						(type none)
					)
				)
			)
			(symbol "L_6u8_12.8A_Coilcraft-XAL7070_1_1"
				(pin passive line
					(at 0 0 0)
					(length 0.508)
					(name "~"
						(effects
							(font
								(size 1.27 1.27)
							)
						)
					)
					(number "1"
						(effects
							(font
								(size 1.27 1.27)
							)
						)
					)
				)
				(pin passive line
					(at 5.08 0 180)
					(length 0.508)
					(name "~"
						(effects
							(font
								(size 1.27 1.27)
							)
						)
					)
					(number "2"
						(effects
							(font
								(size 1.27 1.27)
							)
						)
					)
				)
			)
		)
	(symbol "antmicroInterfaceControllers:JHL6340SLLSQ"
			(exclude_from_sim no)
			(in_bom yes)
			(on_board yes)
			(property "Reference" "U"
				(at 71.12 0 0)
				(effects
					(font
						(size 1.27 1.27)
						(thickness 0.15)
					)
					(justify left bottom)
				)
			)
			(property "Value" "JHL6340SLLSQ"
				(at 71.12 -2.54 0)
				(effects
					(font
						(size 1.27 1.27)
						(thickness 0.15)
					)
					(justify left bottom)
					(hide yes)
				)
			)
			(property "Footprint" "antmicro-footprints:JHL6340SLLSQ"
				(at 71.12 -5.08 0)
				(effects
					(font
						(size 1.27 1.27)
						(thickness 0.15)
					)
					(justify left bottom)
					(hide yes)
				)
			)
			(property "Datasheet" "https://www.thunderbolttechnology.net/sites/default/files/18-241_ThunderboltController_Brief_HI.pdf"
				(at 71.12 -7.62 0)
				(effects
					(font
						(size 1.27 1.27)
						(thickness 0.15)
					)
					(justify left bottom)
					(hide yes)
				)
			)
			(property "Description" "Thunderbolt™ 3 Controller, I/O"
				(at 0 0 0)
				(effects
					(font
						(size 1.27 1.27)
					)
					(hide yes)
				)
			)
			(property "Manufacturer" "Intel"
				(at 71.12 -10.16 0)
				(effects
					(font
						(size 1.27 1.27)
						(thickness 0.15)
					)
					(justify left bottom)
					(hide yes)
				)
			)
			(property "MPN" "JHL6340SLLSQ"
				(at 71.12 -12.7 0)
				(effects
					(font
						(size 1.27 1.27)
						(thickness 0.15)
					)
					(justify left bottom)
				)
			)
			(property "Author" "Antmicro"
				(at 71.12 -15.24 0)
				(effects
					(font
						(size 1.27 1.27)
						(thickness 0.15)
					)
					(justify left bottom)
					(hide yes)
				)
			)
			(property "License" "Apache-2.0"
				(at 71.12 -17.78 0)
				(effects
					(font
						(size 1.27 1.27)
						(thickness 0.15)
					)
					(justify left bottom)
					(hide yes)
				)
			)
			(property "ki_locked" ""
				(at 0 0 0)
				(effects
					(font
						(size 1.27 1.27)
					)
				)
			)
			(property "ki_keywords" "IC"
				(at 0 0 0)
				(effects
					(font
						(size 1.27 1.27)
					)
					(hide yes)
				)
			)
			(symbol "JHL6340SLLSQ_1_0"
				(rectangle
					(start 5.08 3.81)
					(end 49.53 -85.09)
					(stroke
						(width 0.254)
						(type default)
					)
					(fill
						(type background)
					)
				)
			)
			(symbol "JHL6340SLLSQ_1_1"
				(pin power_in line
					(at 54.61 -55.88 180)
					(length 5.08)
					(name "SVR_VSS"
						(effects
							(font
								(size 1.27 1.27)
							)
						)
					)
					(number "A1"
						(effects
							(font
								(size 1.27 1.27)
							)
						)
					)
				)
				(pin passive line
					(at 0 -81.28 0)
					(length 5.08)
					(name "VSS_ANA"
						(effects
							(font
								(size 1.27 1.27)
							)
						)
					)
					(number "A10"
						(effects
							(font
								(size 1.27 1.27)
							)
						)
					)
				)
				(pin passive line
					(at 0 -81.28 0)
					(length 5.08) hide
					(name "VSS_ANA"
						(effects
							(font
								(size 1.27 1.27)
							)
						)
					)
					(number "A12"
						(effects
							(font
								(size 1.27 1.27)
							)
						)
					)
				)
				(pin passive line
					(at 0 -81.28 0)
					(length 5.08) hide
					(name "VSS_ANA"
						(effects
							(font
								(size 1.27 1.27)
							)
						)
					)
					(number "A14"
						(effects
							(font
								(size 1.27 1.27)
							)
						)
					)
				)
				(pin passive line
					(at 0 -81.28 0)
					(length 5.08) hide
					(name "VSS_ANA"
						(effects
							(font
								(size 1.27 1.27)
							)
						)
					)
					(number "A16"
						(effects
							(font
								(size 1.27 1.27)
							)
						)
					)
				)
				(pin passive line
					(at 0 -81.28 0)
					(length 5.08) hide
					(name "VSS_ANA"
						(effects
							(font
								(size 1.27 1.27)
							)
						)
					)
					(number "A18"
						(effects
							(font
								(size 1.27 1.27)
							)
						)
					)
				)
				(pin power_in line
					(at 54.61 0 180)
					(length 5.08)
					(name "VCC3P3_SVR"
						(effects
							(font
								(size 1.27 1.27)
							)
						)
					)
					(number "A2"
						(effects
							(font
								(size 1.27 1.27)
							)
						)
					)
				)
				(pin passive line
					(at 0 -81.28 0)
					(length 5.08) hide
					(name "VSS_ANA"
						(effects
							(font
								(size 1.27 1.27)
							)
						)
					)
					(number "A20"
						(effects
							(font
								(size 1.27 1.27)
							)
						)
					)
				)
				(pin passive line
					(at 0 -81.28 0)
					(length 5.08) hide
					(name "VSS_ANA"
						(effects
							(font
								(size 1.27 1.27)
							)
						)
					)
					(number "A22"
						(effects
							(font
								(size 1.27 1.27)
							)
						)
					)
				)
				(pin passive line
					(at 54.61 0 180)
					(length 5.08) hide
					(name "VCC3P3_SVR"
						(effects
							(font
								(size 1.27 1.27)
							)
						)
					)
					(number "A3"
						(effects
							(font
								(size 1.27 1.27)
							)
						)
					)
				)
				(pin passive line
					(at 0 -81.28 0)
					(length 5.08) hide
					(name "VSS_ANA"
						(effects
							(font
								(size 1.27 1.27)
							)
						)
					)
					(number "A6"
						(effects
							(font
								(size 1.27 1.27)
							)
						)
					)
				)
				(pin passive line
					(at 0 -81.28 0)
					(length 5.08) hide
					(name "VSS_ANA"
						(effects
							(font
								(size 1.27 1.27)
							)
						)
					)
					(number "A8"
						(effects
							(font
								(size 1.27 1.27)
							)
						)
					)
				)
				(pin passive line
					(at 0 -81.28 0)
					(length 5.08) hide
					(name "VSS_ANA"
						(effects
							(font
								(size 1.27 1.27)
							)
						)
					)
					(number "AA22"
						(effects
							(font
								(size 1.27 1.27)
							)
						)
					)
				)
				(pin passive line
					(at 0 -81.28 0)
					(length 5.08) hide
					(name "VSS_ANA"
						(effects
							(font
								(size 1.27 1.27)
							)
						)
					)
					(number "AA23"
						(effects
							(font
								(size 1.27 1.27)
							)
						)
					)
				)
				(pin passive line
					(at 54.61 -81.28 180)
					(length 5.08)
					(name "VSS"
						(effects
							(font
								(size 1.27 1.27)
							)
						)
					)
					(number "AB1"
						(effects
							(font
								(size 1.27 1.27)
							)
						)
					)
				)
				(pin passive line
					(at 0 -81.28 0)
					(length 5.08) hide
					(name "VSS_ANA"
						(effects
							(font
								(size 1.27 1.27)
							)
						)
					)
					(number "AB10"
						(effects
							(font
								(size 1.27 1.27)
							)
						)
					)
				)
				(pin passive line
					(at 0 -81.28 0)
					(length 5.08) hide
					(name "VSS_ANA"
						(effects
							(font
								(size 1.27 1.27)
							)
						)
					)
					(number "AB12"
						(effects
							(font
								(size 1.27 1.27)
							)
						)
					)
				)
				(pin passive line
					(at 0 -81.28 0)
					(length 5.08) hide
					(name "VSS_ANA"
						(effects
							(font
								(size 1.27 1.27)
							)
						)
					)
					(number "AB14"
						(effects
							(font
								(size 1.27 1.27)
							)
						)
					)
				)
				(pin passive line
					(at 0 -81.28 0)
					(length 5.08) hide
					(name "VSS_ANA"
						(effects
							(font
								(size 1.27 1.27)
							)
						)
					)
					(number "AB16"
						(effects
							(font
								(size 1.27 1.27)
							)
						)
					)
				)
				(pin passive line
					(at 0 -81.28 0)
					(length 5.08) hide
					(name "VSS_ANA"
						(effects
							(font
								(size 1.27 1.27)
							)
						)
					)
					(number "AB18"
						(effects
							(font
								(size 1.27 1.27)
							)
						)
					)
				)
				(pin passive line
					(at 0 -81.28 0)
					(length 5.08) hide
					(name "VSS_ANA"
						(effects
							(font
								(size 1.27 1.27)
							)
						)
					)
					(number "AB20"
						(effects
							(font
								(size 1.27 1.27)
							)
						)
					)
				)
				(pin passive line
					(at 0 -81.28 0)
					(length 5.08) hide
					(name "VSS_ANA"
						(effects
							(font
								(size 1.27 1.27)
							)
						)
					)
					(number "AB22"
						(effects
							(font
								(size 1.27 1.27)
							)
						)
					)
				)
				(pin passive line
					(at 0 -81.28 0)
					(length 5.08) hide
					(name "VSS_ANA"
						(effects
							(font
								(size 1.27 1.27)
							)
						)
					)
					(number "AB6"
						(effects
							(font
								(size 1.27 1.27)
							)
						)
					)
				)
				(pin passive line
					(at 0 -81.28 0)
					(length 5.08) hide
					(name "VSS_ANA"
						(effects
							(font
								(size 1.27 1.27)
							)
						)
					)
					(number "AB8"
						(effects
							(font
								(size 1.27 1.27)
							)
						)
					)
				)
				(pin passive line
					(at 0 -81.28 0)
					(length 5.08) hide
					(name "VSS_ANA"
						(effects
							(font
								(size 1.27 1.27)
							)
						)
					)
					(number "AC10"
						(effects
							(font
								(size 1.27 1.27)
							)
						)
					)
				)
				(pin passive line
					(at 0 -81.28 0)
					(length 5.08) hide
					(name "VSS_ANA"
						(effects
							(font
								(size 1.27 1.27)
							)
						)
					)
					(number "AC12"
						(effects
							(font
								(size 1.27 1.27)
							)
						)
					)
				)
				(pin passive line
					(at 0 -81.28 0)
					(length 5.08) hide
					(name "VSS_ANA"
						(effects
							(font
								(size 1.27 1.27)
							)
						)
					)
					(number "AC14"
						(effects
							(font
								(size 1.27 1.27)
							)
						)
					)
				)
				(pin passive line
					(at 0 -81.28 0)
					(length 5.08) hide
					(name "VSS_ANA"
						(effects
							(font
								(size 1.27 1.27)
							)
						)
					)
					(number "AC16"
						(effects
							(font
								(size 1.27 1.27)
							)
						)
					)
				)
				(pin passive line
					(at 0 -81.28 0)
					(length 5.08) hide
					(name "VSS_ANA"
						(effects
							(font
								(size 1.27 1.27)
							)
						)
					)
					(number "AC18"
						(effects
							(font
								(size 1.27 1.27)
							)
						)
					)
				)
				(pin passive line
					(at 54.61 -81.28 180)
					(length 5.08) hide
					(name "VSS"
						(effects
							(font
								(size 1.27 1.27)
							)
						)
					)
					(number "AC2"
						(effects
							(font
								(size 1.27 1.27)
							)
						)
					)
				)
				(pin passive line
					(at 0 -81.28 0)
					(length 5.08) hide
					(name "VSS_ANA"
						(effects
							(font
								(size 1.27 1.27)
							)
						)
					)
					(number "AC20"
						(effects
							(font
								(size 1.27 1.27)
							)
						)
					)
				)
				(pin passive line
					(at 0 -81.28 0)
					(length 5.08) hide
					(name "VSS_ANA"
						(effects
							(font
								(size 1.27 1.27)
							)
						)
					)
					(number "AC22"
						(effects
							(font
								(size 1.27 1.27)
							)
						)
					)
				)
				(pin passive line
					(at 0 -81.28 0)
					(length 5.08) hide
					(name "VSS_ANA"
						(effects
							(font
								(size 1.27 1.27)
							)
						)
					)
					(number "AC6"
						(effects
							(font
								(size 1.27 1.27)
							)
						)
					)
				)
				(pin passive line
					(at 0 -81.28 0)
					(length 5.08) hide
					(name "VSS_ANA"
						(effects
							(font
								(size 1.27 1.27)
							)
						)
					)
					(number "AC8"
						(effects
							(font
								(size 1.27 1.27)
							)
						)
					)
				)
				(pin passive line
					(at 54.61 -55.88 180)
					(length 5.08) hide
					(name "SVR_VSS"
						(effects
							(font
								(size 1.27 1.27)
							)
						)
					)
					(number "B1"
						(effects
							(font
								(size 1.27 1.27)
							)
						)
					)
				)
				(pin passive line
					(at 0 -81.28 0)
					(length 5.08) hide
					(name "VSS_ANA"
						(effects
							(font
								(size 1.27 1.27)
							)
						)
					)
					(number "B10"
						(effects
							(font
								(size 1.27 1.27)
							)
						)
					)
				)
				(pin passive line
					(at 0 -81.28 0)
					(length 5.08) hide
					(name "VSS_ANA"
						(effects
							(font
								(size 1.27 1.27)
							)
						)
					)
					(number "B12"
						(effects
							(font
								(size 1.27 1.27)
							)
						)
					)
				)
				(pin passive line
					(at 0 -81.28 0)
					(length 5.08) hide
					(name "VSS_ANA"
						(effects
							(font
								(size 1.27 1.27)
							)
						)
					)
					(number "B14"
						(effects
							(font
								(size 1.27 1.27)
							)
						)
					)
				)
				(pin passive line
					(at 0 -81.28 0)
					(length 5.08) hide
					(name "VSS_ANA"
						(effects
							(font
								(size 1.27 1.27)
							)
						)
					)
					(number "B16"
						(effects
							(font
								(size 1.27 1.27)
							)
						)
					)
				)
				(pin passive line
					(at 0 -81.28 0)
					(length 5.08) hide
					(name "VSS_ANA"
						(effects
							(font
								(size 1.27 1.27)
							)
						)
					)
					(number "B18"
						(effects
							(font
								(size 1.27 1.27)
							)
						)
					)
				)
				(pin passive line
					(at 54.61 -55.88 180)
					(length 5.08) hide
					(name "SVR_VSS"
						(effects
							(font
								(size 1.27 1.27)
							)
						)
					)
					(number "B2"
						(effects
							(font
								(size 1.27 1.27)
							)
						)
					)
				)
				(pin passive line
					(at 0 -81.28 0)
					(length 5.08) hide
					(name "VSS_ANA"
						(effects
							(font
								(size 1.27 1.27)
							)
						)
					)
					(number "B20"
						(effects
							(font
								(size 1.27 1.27)
							)
						)
					)
				)
				(pin passive line
					(at 0 -81.28 0)
					(length 5.08) hide
					(name "VSS_ANA"
						(effects
							(font
								(size 1.27 1.27)
							)
						)
					)
					(number "B22"
						(effects
							(font
								(size 1.27 1.27)
							)
						)
					)
				)
				(pin passive line
					(at 54.61 0 180)
					(length 5.08) hide
					(name "VCC3P3_SVR"
						(effects
							(font
								(size 1.27 1.27)
							)
						)
					)
					(number "B3"
						(effects
							(font
								(size 1.27 1.27)
							)
						)
					)
				)
				(pin passive line
					(at 0 -81.28 0)
					(length 5.08) hide
					(name "VSS_ANA"
						(effects
							(font
								(size 1.27 1.27)
							)
						)
					)
					(number "B6"
						(effects
							(font
								(size 1.27 1.27)
							)
						)
					)
				)
				(pin passive line
					(at 0 -81.28 0)
					(length 5.08) hide
					(name "VSS_ANA"
						(effects
							(font
								(size 1.27 1.27)
							)
						)
					)
					(number "B8"
						(effects
							(font
								(size 1.27 1.27)
							)
						)
					)
				)
				(pin power_out line
					(at 54.61 -53.34 180)
					(length 5.08)
					(name "SVR_IND"
						(effects
							(font
								(size 1.27 1.27)
							)
						)
					)
					(number "C1"
						(effects
							(font
								(size 1.27 1.27)
							)
						)
					)
				)
				(pin passive line
					(at 54.61 -53.34 180)
					(length 5.08) hide
					(name "SVR_IND"
						(effects
							(font
								(size 1.27 1.27)
							)
						)
					)
					(number "C2"
						(effects
							(font
								(size 1.27 1.27)
							)
						)
					)
				)
				(pin passive line
					(at 54.61 -53.34 180)
					(length 5.08) hide
					(name "SVR_IND"
						(effects
							(font
								(size 1.27 1.27)
							)
						)
					)
					(number "D1"
						(effects
							(font
								(size 1.27 1.27)
							)
						)
					)
				)
				(pin passive line
					(at 0 -81.28 0)
					(length 5.08) hide
					(name "VSS_ANA"
						(effects
							(font
								(size 1.27 1.27)
							)
						)
					)
					(number "D11"
						(effects
							(font
								(size 1.27 1.27)
							)
						)
					)
				)
				(pin passive line
					(at 0 -81.28 0)
					(length 5.08) hide
					(name "VSS_ANA"
						(effects
							(font
								(size 1.27 1.27)
							)
						)
					)
					(number "D12"
						(effects
							(font
								(size 1.27 1.27)
							)
						)
					)
				)
				(pin passive line
					(at 0 -81.28 0)
					(length 5.08) hide
					(name "VSS_ANA"
						(effects
							(font
								(size 1.27 1.27)
							)
						)
					)
					(number "D13"
						(effects
							(font
								(size 1.27 1.27)
							)
						)
					)
				)
				(pin passive line
					(at 0 -81.28 0)
					(length 5.08) hide
					(name "VSS_ANA"
						(effects
							(font
								(size 1.27 1.27)
							)
						)
					)
					(number "D15"
						(effects
							(font
								(size 1.27 1.27)
							)
						)
					)
				)
				(pin passive line
					(at 0 -81.28 0)
					(length 5.08) hide
					(name "VSS_ANA"
						(effects
							(font
								(size 1.27 1.27)
							)
						)
					)
					(number "D16"
						(effects
							(font
								(size 1.27 1.27)
							)
						)
					)
				)
				(pin passive line
					(at 0 -81.28 0)
					(length 5.08) hide
					(name "VSS_ANA"
						(effects
							(font
								(size 1.27 1.27)
							)
						)
					)
					(number "D18"
						(effects
							(font
								(size 1.27 1.27)
							)
						)
					)
				)
				(pin passive line
					(at 54.61 -81.28 180)
					(length 5.08) hide
					(name "VSS"
						(effects
							(font
								(size 1.27 1.27)
							)
						)
					)
					(number "D5"
						(effects
							(font
								(size 1.27 1.27)
							)
						)
					)
				)
				(pin passive line
					(at 0 -81.28 0)
					(length 5.08) hide
					(name "VSS_ANA"
						(effects
							(font
								(size 1.27 1.27)
							)
						)
					)
					(number "D8"
						(effects
							(font
								(size 1.27 1.27)
							)
						)
					)
				)
				(pin passive line
					(at 0 -81.28 0)
					(length 5.08) hide
					(name "VSS_ANA"
						(effects
							(font
								(size 1.27 1.27)
							)
						)
					)
					(number "D9"
						(effects
							(font
								(size 1.27 1.27)
							)
						)
					)
				)
				(pin passive line
					(at 0 -81.28 0)
					(length 5.08) hide
					(name "VSS_ANA"
						(effects
							(font
								(size 1.27 1.27)
							)
						)
					)
					(number "E11"
						(effects
							(font
								(size 1.27 1.27)
							)
						)
					)
				)
				(pin power_in line
					(at 54.61 -38.1 180)
					(length 5.08)
					(name "VCC0P9_SVR_ANA"
						(effects
							(font
								(size 1.27 1.27)
							)
						)
					)
					(number "E12"
						(effects
							(font
								(size 1.27 1.27)
							)
						)
					)
				)
				(pin passive line
					(at 54.61 -38.1 180)
					(length 5.08) hide
					(name "VCC0P9_SVR_ANA"
						(effects
							(font
								(size 1.27 1.27)
							)
						)
					)
					(number "E13"
						(effects
							(font
								(size 1.27 1.27)
							)
						)
					)
				)
				(pin passive line
					(at 0 -81.28 0)
					(length 5.08) hide
					(name "VSS_ANA"
						(effects
							(font
								(size 1.27 1.27)
							)
						)
					)
					(number "E15"
						(effects
							(font
								(size 1.27 1.27)
							)
						)
					)
				)
				(pin passive line
					(at 0 -81.28 0)
					(length 5.08) hide
					(name "VSS_ANA"
						(effects
							(font
								(size 1.27 1.27)
							)
						)
					)
					(number "E16"
						(effects
							(font
								(size 1.27 1.27)
							)
						)
					)
				)
				(pin passive line
					(at 0 -81.28 0)
					(length 5.08) hide
					(name "VSS_ANA"
						(effects
							(font
								(size 1.27 1.27)
							)
						)
					)
					(number "E22"
						(effects
							(font
								(size 1.27 1.27)
							)
						)
					)
				)
				(pin passive line
					(at 0 -81.28 0)
					(length 5.08) hide
					(name "VSS_ANA"
						(effects
							(font
								(size 1.27 1.27)
							)
						)
					)
					(number "E23"
						(effects
							(font
								(size 1.27 1.27)
							)
						)
					)
				)
				(pin passive line
					(at 54.61 -81.28 180)
					(length 5.08) hide
					(name "VSS"
						(effects
							(font
								(size 1.27 1.27)
							)
						)
					)
					(number "E4"
						(effects
							(font
								(size 1.27 1.27)
							)
						)
					)
				)
				(pin passive line
					(at 54.61 -81.28 180)
					(length 5.08) hide
					(name "VSS"
						(effects
							(font
								(size 1.27 1.27)
							)
						)
					)
					(number "E5"
						(effects
							(font
								(size 1.27 1.27)
							)
						)
					)
				)
				(pin passive line
					(at 54.61 -81.28 180)
					(length 5.08) hide
					(name "VSS"
						(effects
							(font
								(size 1.27 1.27)
							)
						)
					)
					(number "E6"
						(effects
							(font
								(size 1.27 1.27)
							)
						)
					)
				)
				(pin passive line
					(at 0 -81.28 0)
					(length 5.08) hide
					(name "VSS_ANA"
						(effects
							(font
								(size 1.27 1.27)
							)
						)
					)
					(number "E8"
						(effects
							(font
								(size 1.27 1.27)
							)
						)
					)
				)
				(pin passive line
					(at 0 -81.28 0)
					(length 5.08) hide
					(name "VSS_ANA"
						(effects
							(font
								(size 1.27 1.27)
							)
						)
					)
					(number "E9"
						(effects
							(font
								(size 1.27 1.27)
							)
						)
					)
				)
				(pin passive line
					(at 54.61 -38.1 180)
					(length 5.08) hide
					(name "VCC0P9_SVR_ANA"
						(effects
							(font
								(size 1.27 1.27)
							)
						)
					)
					(number "F11"
						(effects
							(font
								(size 1.27 1.27)
							)
						)
					)
				)
				(pin passive line
					(at 54.61 -38.1 180)
					(length 5.08) hide
					(name "VCC0P9_SVR_ANA"
						(effects
							(font
								(size 1.27 1.27)
							)
						)
					)
					(number "F12"
						(effects
							(font
								(size 1.27 1.27)
							)
						)
					)
				)
				(pin passive line
					(at 54.61 -38.1 180)
					(length 5.08) hide
					(name "VCC0P9_SVR_ANA"
						(effects
							(font
								(size 1.27 1.27)
							)
						)
					)
					(number "F13"
						(effects
							(font
								(size 1.27 1.27)
							)
						)
					)
				)
				(pin passive line
					(at 54.61 -38.1 180)
					(length 5.08) hide
					(name "VCC0P9_SVR_ANA"
						(effects
							(font
								(size 1.27 1.27)
							)
						)
					)
					(number "F15"
						(effects
							(font
								(size 1.27 1.27)
							)
						)
					)
				)
				(pin passive line
					(at 0 -81.28 0)
					(length 5.08) hide
					(name "VSS_ANA"
						(effects
							(font
								(size 1.27 1.27)
							)
						)
					)
					(number "F16"
						(effects
							(font
								(size 1.27 1.27)
							)
						)
					)
				)
				(pin power_in line
					(at 54.61 -71.12 180)
					(length 5.08)
					(name "VCC0P9_LVR"
						(effects
							(font
								(size 1.27 1.27)
							)
						)
					)
					(number "F18"
						(effects
							(font
								(size 1.27 1.27)
							)
						)
					)
				)
				(pin passive line
					(at 0 -81.28 0)
					(length 5.08) hide
					(name "VSS_ANA"
						(effects
							(font
								(size 1.27 1.27)
							)
						)
					)
					(number "F20"
						(effects
							(font
								(size 1.27 1.27)
							)
						)
					)
				)
				(pin passive line
					(at 54.61 -81.28 180)
					(length 5.08) hide
					(name "VSS"
						(effects
							(font
								(size 1.27 1.27)
							)
						)
					)
					(number "F5"
						(effects
							(font
								(size 1.27 1.27)
							)
						)
					)
				)
				(pin passive line
					(at 54.61 -81.28 180)
					(length 5.08) hide
					(name "VSS"
						(effects
							(font
								(size 1.27 1.27)
							)
						)
					)
					(number "F6"
						(effects
							(font
								(size 1.27 1.27)
							)
						)
					)
				)
				(pin power_in line
					(at 54.61 -2.54 180)
					(length 5.08)
					(name "VCC3P3_SX"
						(effects
							(font
								(size 1.27 1.27)
							)
						)
					)
					(number "F8"
						(effects
							(font
								(size 1.27 1.27)
							)
						)
					)
				)
				(pin passive line
					(at 0 -81.28 0)
					(length 5.08) hide
					(name "VSS_ANA"
						(effects
							(font
								(size 1.27 1.27)
							)
						)
					)
					(number "F9"
						(effects
							(font
								(size 1.27 1.27)
							)
						)
					)
				)
				(pin passive line
					(at 0 -81.28 0)
					(length 5.08) hide
					(name "VSS_ANA"
						(effects
							(font
								(size 1.27 1.27)
							)
						)
					)
					(number "G22"
						(effects
							(font
								(size 1.27 1.27)
							)
						)
					)
				)
				(pin passive line
					(at 0 -81.28 0)
					(length 5.08) hide
					(name "VSS_ANA"
						(effects
							(font
								(size 1.27 1.27)
							)
						)
					)
					(number "G23"
						(effects
							(font
								(size 1.27 1.27)
							)
						)
					)
				)
				(pin passive line
					(at 0 -81.28 0)
					(length 5.08) hide
					(name "VSS_ANA"
						(effects
							(font
								(size 1.27 1.27)
							)
						)
					)
					(number "H1"
						(effects
							(font
								(size 1.27 1.27)
							)
						)
					)
				)
				(pin power_in line
					(at 54.61 -73.66 180)
					(length 5.08)
					(name "VCC0P9_LVR_SENSE"
						(effects
							(font
								(size 1.27 1.27)
							)
						)
					)
					(number "H11"
						(effects
							(font
								(size 1.27 1.27)
							)
						)
					)
				)
				(pin passive line
					(at 0 -81.28 0)
					(length 5.08) hide
					(name "VSS_ANA"
						(effects
							(font
								(size 1.27 1.27)
							)
						)
					)
					(number "H12"
						(effects
							(font
								(size 1.27 1.27)
							)
						)
					)
				)
				(pin passive line
					(at 0 -81.28 0)
					(length 5.08) hide
					(name "VSS_ANA"
						(effects
							(font
								(size 1.27 1.27)
							)
						)
					)
					(number "H13"
						(effects
							(font
								(size 1.27 1.27)
							)
						)
					)
				)
				(pin passive line
					(at 0 -81.28 0)
					(length 5.08) hide
					(name "VSS_ANA"
						(effects
							(font
								(size 1.27 1.27)
							)
						)
					)
					(number "H15"
						(effects
							(font
								(size 1.27 1.27)
							)
						)
					)
				)
				(pin passive line
					(at 0 -81.28 0)
					(length 5.08) hide
					(name "VSS_ANA"
						(effects
							(font
								(size 1.27 1.27)
							)
						)
					)
					(number "H16"
						(effects
							(font
								(size 1.27 1.27)
							)
						)
					)
				)
				(pin passive line
					(at 54.61 -71.12 180)
					(length 5.08) hide
					(name "VCC0P9_LVR"
						(effects
							(font
								(size 1.27 1.27)
							)
						)
					)
					(number "H18"
						(effects
							(font
								(size 1.27 1.27)
							)
						)
					)
				)
				(pin passive line
					(at 0 -81.28 0)
					(length 5.08) hide
					(name "VSS_ANA"
						(effects
							(font
								(size 1.27 1.27)
							)
						)
					)
					(number "H2"
						(effects
							(font
								(size 1.27 1.27)
							)
						)
					)
				)
				(pin passive line
					(at 0 -81.28 0)
					(length 5.08) hide
					(name "VSS_ANA"
						(effects
							(font
								(size 1.27 1.27)
							)
						)
					)
					(number "H20"
						(effects
							(font
								(size 1.27 1.27)
							)
						)
					)
				)
				(pin passive line
					(at 54.61 -81.28 180)
					(length 5.08) hide
					(name "VSS"
						(effects
							(font
								(size 1.27 1.27)
							)
						)
					)
					(number "H5"
						(effects
							(font
								(size 1.27 1.27)
							)
						)
					)
				)
				(pin passive line
					(at 54.61 -81.28 180)
					(length 5.08) hide
					(name "VSS"
						(effects
							(font
								(size 1.27 1.27)
							)
						)
					)
					(number "H8"
						(effects
							(font
								(size 1.27 1.27)
							)
						)
					)
				)
				(pin power_in line
					(at 54.61 -5.08 180)
					(length 5.08)
					(name "VCC3P3A"
						(effects
							(font
								(size 1.27 1.27)
							)
						)
					)
					(number "H9"
						(effects
							(font
								(size 1.27 1.27)
							)
						)
					)
				)
				(pin passive line
					(at 54.61 -71.12 180)
					(length 5.08) hide
					(name "VCC0P9_LVR"
						(effects
							(font
								(size 1.27 1.27)
							)
						)
					)
					(number "J11"
						(effects
							(font
								(size 1.27 1.27)
							)
						)
					)
				)
				(pin passive line
					(at 54.61 -81.28 180)
					(length 5.08) hide
					(name "VSS"
						(effects
							(font
								(size 1.27 1.27)
							)
						)
					)
					(number "J12"
						(effects
							(font
								(size 1.27 1.27)
							)
						)
					)
				)
				(pin passive line
					(at 54.61 -81.28 180)
					(length 5.08) hide
					(name "VSS"
						(effects
							(font
								(size 1.27 1.27)
							)
						)
					)
					(number "J13"
						(effects
							(font
								(size 1.27 1.27)
							)
						)
					)
				)
				(pin passive line
					(at 54.61 -81.28 180)
					(length 5.08) hide
					(name "VSS"
						(effects
							(font
								(size 1.27 1.27)
							)
						)
					)
					(number "J15"
						(effects
							(font
								(size 1.27 1.27)
							)
						)
					)
				)
				(pin power_in line
					(at 0 -73.66 0)
					(length 5.08)
					(name "VCC3P3_ANA_USB2"
						(effects
							(font
								(size 1.27 1.27)
							)
						)
					)
					(number "J16"
						(effects
							(font
								(size 1.27 1.27)
							)
						)
					)
				)
				(pin passive line
					(at 0 -81.28 0)
					(length 5.08) hide
					(name "VSS_ANA"
						(effects
							(font
								(size 1.27 1.27)
							)
						)
					)
					(number "J18"
						(effects
							(font
								(size 1.27 1.27)
							)
						)
					)
				)
				(pin passive line
					(at 0 -81.28 0)
					(length 5.08) hide
					(name "VSS_ANA"
						(effects
							(font
								(size 1.27 1.27)
							)
						)
					)
					(number "J19"
						(effects
							(font
								(size 1.27 1.27)
							)
						)
					)
				)
				(pin passive line
					(at 0 -81.28 0)
					(length 5.08) hide
					(name "VSS_ANA"
						(effects
							(font
								(size 1.27 1.27)
							)
						)
					)
					(number "J20"
						(effects
							(font
								(size 1.27 1.27)
							)
						)
					)
				)
				(pin passive line
					(at 0 -81.28 0)
					(length 5.08) hide
					(name "VSS_ANA"
						(effects
							(font
								(size 1.27 1.27)
							)
						)
					)
					(number "J22"
						(effects
							(font
								(size 1.27 1.27)
							)
						)
					)
				)
				(pin passive line
					(at 0 -81.28 0)
					(length 5.08) hide
					(name "VSS_ANA"
						(effects
							(font
								(size 1.27 1.27)
							)
						)
					)
					(number "J23"
						(effects
							(font
								(size 1.27 1.27)
							)
						)
					)
				)
				(pin passive line
					(at 0 -81.28 0)
					(length 5.08) hide
					(name "VSS_ANA"
						(effects
							(font
								(size 1.27 1.27)
							)
						)
					)
					(number "J5"
						(effects
							(font
								(size 1.27 1.27)
							)
						)
					)
				)
				(pin passive line
					(at 54.61 -81.28 180)
					(length 5.08) hide
					(name "VSS"
						(effects
							(font
								(size 1.27 1.27)
							)
						)
					)
					(number "J8"
						(effects
							(font
								(size 1.27 1.27)
							)
						)
					)
				)
				(pin power_in line
					(at 54.61 -40.64 180)
					(length 5.08)
					(name "VCC0P9_SVR_SENSE"
						(effects
							(font
								(size 1.27 1.27)
							)
						)
					)
					(number "J9"
						(effects
							(font
								(size 1.27 1.27)
							)
						)
					)
				)
				(pin passive line
					(at 0 -81.28 0)
					(length 5.08) hide
					(name "VSS_ANA"
						(effects
							(font
								(size 1.27 1.27)
							)
						)
					)
					(number "K1"
						(effects
							(font
								(size 1.27 1.27)
							)
						)
					)
				)
				(pin passive line
					(at 0 -81.28 0)
					(length 5.08) hide
					(name "VSS_ANA"
						(effects
							(font
								(size 1.27 1.27)
							)
						)
					)
					(number "K2"
						(effects
							(font
								(size 1.27 1.27)
							)
						)
					)
				)
				(pin power_in line
					(at 0 0 0)
					(length 5.08)
					(name "VCC0P9_DP"
						(effects
							(font
								(size 1.27 1.27)
							)
						)
					)
					(number "L11"
						(effects
							(font
								(size 1.27 1.27)
							)
						)
					)
				)
				(pin passive line
					(at 0 0 0)
					(length 5.08) hide
					(name "VCC0P9_DP"
						(effects
							(font
								(size 1.27 1.27)
							)
						)
					)
					(number "L12"
						(effects
							(font
								(size 1.27 1.27)
							)
						)
					)
				)
				(pin passive line
					(at 54.61 -81.28 180)
					(length 5.08) hide
					(name "VSS"
						(effects
							(font
								(size 1.27 1.27)
							)
						)
					)
					(number "L13"
						(effects
							(font
								(size 1.27 1.27)
							)
						)
					)
				)
				(pin power_in line
					(at 0 -71.12 0)
					(length 5.08)
					(name "VCC3P3_ANA_PCIE"
						(effects
							(font
								(size 1.27 1.27)
							)
						)
					)
					(number "L16"
						(effects
							(font
								(size 1.27 1.27)
							)
						)
					)
				)
				(pin power_in line
					(at 0 -22.86 0)
					(length 5.08)
					(name "VCC0P9_ANA_PCIE_2"
						(effects
							(font
								(size 1.27 1.27)
							)
						)
					)
					(number "L18"
						(effects
							(font
								(size 1.27 1.27)
							)
						)
					)
				)
				(pin power_in line
					(at 0 -20.32 0)
					(length 5.08)
					(name "VCC0P9_ANA_PCIE_1"
						(effects
							(font
								(size 1.27 1.27)
							)
						)
					)
					(number "L19"
						(effects
							(font
								(size 1.27 1.27)
							)
						)
					)
				)
				(pin passive line
					(at 0 -81.28 0)
					(length 5.08) hide
					(name "VSS_ANA"
						(effects
							(font
								(size 1.27 1.27)
							)
						)
					)
					(number "L20"
						(effects
							(font
								(size 1.27 1.27)
							)
						)
					)
				)
				(pin passive line
					(at 0 -81.28 0)
					(length 5.08) hide
					(name "VSS_ANA"
						(effects
							(font
								(size 1.27 1.27)
							)
						)
					)
					(number "L22"
						(effects
							(font
								(size 1.27 1.27)
							)
						)
					)
				)
				(pin passive line
					(at 0 -81.28 0)
					(length 5.08) hide
					(name "VSS_ANA"
						(effects
							(font
								(size 1.27 1.27)
							)
						)
					)
					(number "L23"
						(effects
							(font
								(size 1.27 1.27)
							)
						)
					)
				)
				(pin passive line
					(at 0 -81.28 0)
					(length 5.08) hide
					(name "VSS_ANA"
						(effects
							(font
								(size 1.27 1.27)
							)
						)
					)
					(number "L5"
						(effects
							(font
								(size 1.27 1.27)
							)
						)
					)
				)
				(pin power_in line
					(at 0 -2.54 0)
					(length 5.08)
					(name "VCC0P9_ANA_DPSRC"
						(effects
							(font
								(size 1.27 1.27)
							)
						)
					)
					(number "L6"
						(effects
							(font
								(size 1.27 1.27)
							)
						)
					)
				)
				(pin passive line
					(at 0 0 0)
					(length 5.08) hide
					(name "VCC0P9_DP"
						(effects
							(font
								(size 1.27 1.27)
							)
						)
					)
					(number "L8"
						(effects
							(font
								(size 1.27 1.27)
							)
						)
					)
				)
				(pin power_in line
					(at 54.61 -35.56 180)
					(length 5.08)
					(name "VCC0P9_SVR"
						(effects
							(font
								(size 1.27 1.27)
							)
						)
					)
					(number "L9"
						(effects
							(font
								(size 1.27 1.27)
							)
						)
					)
				)
				(pin passive line
					(at 0 -81.28 0)
					(length 5.08) hide
					(name "VSS_ANA"
						(effects
							(font
								(size 1.27 1.27)
							)
						)
					)
					(number "M1"
						(effects
							(font
								(size 1.27 1.27)
							)
						)
					)
				)
				(pin passive line
					(at 54.61 -81.28 180)
					(length 5.08) hide
					(name "VSS"
						(effects
							(font
								(size 1.27 1.27)
							)
						)
					)
					(number "M11"
						(effects
							(font
								(size 1.27 1.27)
							)
						)
					)
				)
				(pin passive line
					(at 54.61 -81.28 180)
					(length 5.08) hide
					(name "VSS"
						(effects
							(font
								(size 1.27 1.27)
							)
						)
					)
					(number "M12"
						(effects
							(font
								(size 1.27 1.27)
							)
						)
					)
				)
				(pin power_in line
					(at 0 -17.78 0)
					(length 5.08)
					(name "VCC0P9_PCIE"
						(effects
							(font
								(size 1.27 1.27)
							)
						)
					)
					(number "M13"
						(effects
							(font
								(size 1.27 1.27)
							)
						)
					)
				)
				(pin passive line
					(at 0 -17.78 0)
					(length 5.08) hide
					(name "VCC0P9_PCIE"
						(effects
							(font
								(size 1.27 1.27)
							)
						)
					)
					(number "M15"
						(effects
							(font
								(size 1.27 1.27)
							)
						)
					)
				)
				(pin passive line
					(at 0 -17.78 0)
					(length 5.08) hide
					(name "VCC0P9_PCIE"
						(effects
							(font
								(size 1.27 1.27)
							)
						)
					)
					(number "M16"
						(effects
							(font
								(size 1.27 1.27)
							)
						)
					)
				)
				(pin passive line
					(at 0 -22.86 0)
					(length 5.08) hide
					(name "VCC0P9_ANA_PCIE_2"
						(effects
							(font
								(size 1.27 1.27)
							)
						)
					)
					(number "M18"
						(effects
							(font
								(size 1.27 1.27)
							)
						)
					)
				)
				(pin passive line
					(at 0 -81.28 0)
					(length 5.08) hide
					(name "VSS_ANA"
						(effects
							(font
								(size 1.27 1.27)
							)
						)
					)
					(number "M19"
						(effects
							(font
								(size 1.27 1.27)
							)
						)
					)
				)
				(pin passive line
					(at 0 -81.28 0)
					(length 5.08) hide
					(name "VSS_ANA"
						(effects
							(font
								(size 1.27 1.27)
							)
						)
					)
					(number "M2"
						(effects
							(font
								(size 1.27 1.27)
							)
						)
					)
				)
				(pin passive line
					(at 0 -81.28 0)
					(length 5.08) hide
					(name "VSS_ANA"
						(effects
							(font
								(size 1.27 1.27)
							)
						)
					)
					(number "M20"
						(effects
							(font
								(size 1.27 1.27)
							)
						)
					)
				)
				(pin passive line
					(at 0 -81.28 0)
					(length 5.08) hide
					(name "VSS_ANA"
						(effects
							(font
								(size 1.27 1.27)
							)
						)
					)
					(number "M5"
						(effects
							(font
								(size 1.27 1.27)
							)
						)
					)
				)
				(pin passive line
					(at 0 -2.54 0)
					(length 5.08) hide
					(name "VCC0P9_ANA_DPSRC"
						(effects
							(font
								(size 1.27 1.27)
							)
						)
					)
					(number "M6"
						(effects
							(font
								(size 1.27 1.27)
							)
						)
					)
				)
				(pin passive line
					(at 0 0 0)
					(length 5.08) hide
					(name "VCC0P9_DP"
						(effects
							(font
								(size 1.27 1.27)
							)
						)
					)
					(number "M8"
						(effects
							(font
								(size 1.27 1.27)
							)
						)
					)
				)
				(pin passive line
					(at 54.61 -35.56 180)
					(length 5.08) hide
					(name "VCC0P9_SVR"
						(effects
							(font
								(size 1.27 1.27)
							)
						)
					)
					(number "M9"
						(effects
							(font
								(size 1.27 1.27)
							)
						)
					)
				)
				(pin passive line
					(at 54.61 -81.28 180)
					(length 5.08) hide
					(name "VSS"
						(effects
							(font
								(size 1.27 1.27)
							)
						)
					)
					(number "N11"
						(effects
							(font
								(size 1.27 1.27)
							)
						)
					)
				)
				(pin passive line
					(at 54.61 -81.28 180)
					(length 5.08) hide
					(name "VSS"
						(effects
							(font
								(size 1.27 1.27)
							)
						)
					)
					(number "N12"
						(effects
							(font
								(size 1.27 1.27)
							)
						)
					)
				)
				(pin passive line
					(at 54.61 -81.28 180)
					(length 5.08) hide
					(name "VSS"
						(effects
							(font
								(size 1.27 1.27)
							)
						)
					)
					(number "N13"
						(effects
							(font
								(size 1.27 1.27)
							)
						)
					)
				)
				(pin passive line
					(at 0 -22.86 0)
					(length 5.08) hide
					(name "VCC0P9_ANA_PCIE_2"
						(effects
							(font
								(size 1.27 1.27)
							)
						)
					)
					(number "N18"
						(effects
							(font
								(size 1.27 1.27)
							)
						)
					)
				)
				(pin passive line
					(at 0 -20.32 0)
					(length 5.08) hide
					(name "VCC0P9_ANA_PCIE_1"
						(effects
							(font
								(size 1.27 1.27)
							)
						)
					)
					(number "N19"
						(effects
							(font
								(size 1.27 1.27)
							)
						)
					)
				)
				(pin passive line
					(at 0 -81.28 0)
					(length 5.08) hide
					(name "VSS_ANA"
						(effects
							(font
								(size 1.27 1.27)
							)
						)
					)
					(number "N20"
						(effects
							(font
								(size 1.27 1.27)
							)
						)
					)
				)
				(pin passive line
					(at 0 -81.28 0)
					(length 5.08) hide
					(name "VSS_ANA"
						(effects
							(font
								(size 1.27 1.27)
							)
						)
					)
					(number "N22"
						(effects
							(font
								(size 1.27 1.27)
							)
						)
					)
				)
				(pin passive line
					(at 0 -81.28 0)
					(length 5.08) hide
					(name "VSS_ANA"
						(effects
							(font
								(size 1.27 1.27)
							)
						)
					)
					(number "N23"
						(effects
							(font
								(size 1.27 1.27)
							)
						)
					)
				)
				(pin passive line
					(at 0 -81.28 0)
					(length 5.08) hide
					(name "VSS_ANA"
						(effects
							(font
								(size 1.27 1.27)
							)
						)
					)
					(number "N5"
						(effects
							(font
								(size 1.27 1.27)
							)
						)
					)
				)
				(pin passive line
					(at 54.61 -81.28 180)
					(length 5.08) hide
					(name "VSS"
						(effects
							(font
								(size 1.27 1.27)
							)
						)
					)
					(number "N8"
						(effects
							(font
								(size 1.27 1.27)
							)
						)
					)
				)
				(pin passive line
					(at 54.61 -81.28 180)
					(length 5.08) hide
					(name "VSS"
						(effects
							(font
								(size 1.27 1.27)
							)
						)
					)
					(number "N9"
						(effects
							(font
								(size 1.27 1.27)
							)
						)
					)
				)
				(pin passive line
					(at 0 -81.28 0)
					(length 5.08) hide
					(name "VSS_ANA"
						(effects
							(font
								(size 1.27 1.27)
							)
						)
					)
					(number "P1"
						(effects
							(font
								(size 1.27 1.27)
							)
						)
					)
				)
				(pin passive line
					(at 0 -81.28 0)
					(length 5.08) hide
					(name "VSS_ANA"
						(effects
							(font
								(size 1.27 1.27)
							)
						)
					)
					(number "P2"
						(effects
							(font
								(size 1.27 1.27)
							)
						)
					)
				)
				(pin power_in line
					(at 0 -53.34 0)
					(length 5.08)
					(name "VCC0P9_CIO"
						(effects
							(font
								(size 1.27 1.27)
							)
						)
					)
					(number "R11"
						(effects
							(font
								(size 1.27 1.27)
							)
						)
					)
				)
				(pin passive line
					(at 0 -53.34 0)
					(length 5.08) hide
					(name "VCC0P9_CIO"
						(effects
							(font
								(size 1.27 1.27)
							)
						)
					)
					(number "R12"
						(effects
							(font
								(size 1.27 1.27)
							)
						)
					)
				)
				(pin power_in line
					(at 54.61 -17.78 180)
					(length 5.08)
					(name "VCC3P3_S0"
						(effects
							(font
								(size 1.27 1.27)
							)
						)
					)
					(number "R13"
						(effects
							(font
								(size 1.27 1.27)
							)
						)
					)
				)
				(pin power_in line
					(at 0 -35.56 0)
					(length 5.08)
					(name "VCC0P9_USB"
						(effects
							(font
								(size 1.27 1.27)
							)
						)
					)
					(number "R15"
						(effects
							(font
								(size 1.27 1.27)
							)
						)
					)
				)
				(pin passive line
					(at 0 -35.56 0)
					(length 5.08) hide
					(name "VCC0P9_USB"
						(effects
							(font
								(size 1.27 1.27)
							)
						)
					)
					(number "R16"
						(effects
							(font
								(size 1.27 1.27)
							)
						)
					)
				)
				(pin passive line
					(at 0 -81.28 0)
					(length 5.08) hide
					(name "VSS_ANA"
						(effects
							(font
								(size 1.27 1.27)
							)
						)
					)
					(number "R18"
						(effects
							(font
								(size 1.27 1.27)
							)
						)
					)
				)
				(pin passive line
					(at 0 -81.28 0)
					(length 5.08) hide
					(name "VSS_ANA"
						(effects
							(font
								(size 1.27 1.27)
							)
						)
					)
					(number "R19"
						(effects
							(font
								(size 1.27 1.27)
							)
						)
					)
				)
				(pin passive line
					(at 0 -81.28 0)
					(length 5.08) hide
					(name "VSS_ANA"
						(effects
							(font
								(size 1.27 1.27)
							)
						)
					)
					(number "R20"
						(effects
							(font
								(size 1.27 1.27)
							)
						)
					)
				)
				(pin passive line
					(at 0 -81.28 0)
					(length 5.08) hide
					(name "VSS_ANA"
						(effects
							(font
								(size 1.27 1.27)
							)
						)
					)
					(number "R22"
						(effects
							(font
								(size 1.27 1.27)
							)
						)
					)
				)
				(pin passive line
					(at 0 -81.28 0)
					(length 5.08) hide
					(name "VSS_ANA"
						(effects
							(font
								(size 1.27 1.27)
							)
						)
					)
					(number "R23"
						(effects
							(font
								(size 1.27 1.27)
							)
						)
					)
				)
				(pin passive line
					(at 0 -81.28 0)
					(length 5.08) hide
					(name "VSS_ANA"
						(effects
							(font
								(size 1.27 1.27)
							)
						)
					)
					(number "R5"
						(effects
							(font
								(size 1.27 1.27)
							)
						)
					)
				)
				(pin power_in line
					(at 54.61 -20.32 180)
					(length 5.08)
					(name "VCC3P3_LC"
						(effects
							(font
								(size 1.27 1.27)
							)
						)
					)
					(number "R6"
						(effects
							(font
								(size 1.27 1.27)
							)
						)
					)
				)
				(pin passive line
					(at 0 -53.34 0)
					(length 5.08) hide
					(name "VCC0P9_CIO"
						(effects
							(font
								(size 1.27 1.27)
							)
						)
					)
					(number "R8"
						(effects
							(font
								(size 1.27 1.27)
							)
						)
					)
				)
				(pin passive line
					(at 0 -53.34 0)
					(length 5.08) hide
					(name "VCC0P9_CIO"
						(effects
							(font
								(size 1.27 1.27)
							)
						)
					)
					(number "R9"
						(effects
							(font
								(size 1.27 1.27)
							)
						)
					)
				)
				(pin passive line
					(at 0 -81.28 0)
					(length 5.08) hide
					(name "VSS_ANA"
						(effects
							(font
								(size 1.27 1.27)
							)
						)
					)
					(number "T1"
						(effects
							(font
								(size 1.27 1.27)
							)
						)
					)
				)
				(pin passive line
					(at 0 0 0)
					(length 5.08) hide
					(name "VCC0P9_DP"
						(effects
							(font
								(size 1.27 1.27)
							)
						)
					)
					(number "T11"
						(effects
							(font
								(size 1.27 1.27)
							)
						)
					)
				)
				(pin passive line
					(at 0 0 0)
					(length 5.08) hide
					(name "VCC0P9_DP"
						(effects
							(font
								(size 1.27 1.27)
							)
						)
					)
					(number "T12"
						(effects
							(font
								(size 1.27 1.27)
							)
						)
					)
				)
				(pin passive line
					(at 54.61 -81.28 180)
					(length 5.08) hide
					(name "VSS"
						(effects
							(font
								(size 1.27 1.27)
							)
						)
					)
					(number "T13"
						(effects
							(font
								(size 1.27 1.27)
							)
						)
					)
				)
				(pin passive line
					(at 54.61 -81.28 180)
					(length 5.08) hide
					(name "VSS"
						(effects
							(font
								(size 1.27 1.27)
							)
						)
					)
					(number "T15"
						(effects
							(font
								(size 1.27 1.27)
							)
						)
					)
				)
				(pin passive line
					(at 54.61 -81.28 180)
					(length 5.08) hide
					(name "VSS"
						(effects
							(font
								(size 1.27 1.27)
							)
						)
					)
					(number "T16"
						(effects
							(font
								(size 1.27 1.27)
							)
						)
					)
				)
				(pin passive line
					(at 54.61 -81.28 180)
					(length 5.08) hide
					(name "VSS"
						(effects
							(font
								(size 1.27 1.27)
							)
						)
					)
					(number "T18"
						(effects
							(font
								(size 1.27 1.27)
							)
						)
					)
				)
				(pin passive line
					(at 0 -81.28 0)
					(length 5.08) hide
					(name "VSS_ANA"
						(effects
							(font
								(size 1.27 1.27)
							)
						)
					)
					(number "T2"
						(effects
							(font
								(size 1.27 1.27)
							)
						)
					)
				)
				(pin passive line
					(at 0 -81.28 0)
					(length 5.08) hide
					(name "VSS_ANA"
						(effects
							(font
								(size 1.27 1.27)
							)
						)
					)
					(number "T20"
						(effects
							(font
								(size 1.27 1.27)
							)
						)
					)
				)
				(pin passive line
					(at 0 -81.28 0)
					(length 5.08) hide
					(name "VSS_ANA"
						(effects
							(font
								(size 1.27 1.27)
							)
						)
					)
					(number "T5"
						(effects
							(font
								(size 1.27 1.27)
							)
						)
					)
				)
				(pin passive line
					(at 54.61 -81.28 180)
					(length 5.08) hide
					(name "VSS"
						(effects
							(font
								(size 1.27 1.27)
							)
						)
					)
					(number "T6"
						(effects
							(font
								(size 1.27 1.27)
							)
						)
					)
				)
				(pin passive line
					(at 54.61 -81.28 180)
					(length 5.08) hide
					(name "VSS"
						(effects
							(font
								(size 1.27 1.27)
							)
						)
					)
					(number "T8"
						(effects
							(font
								(size 1.27 1.27)
							)
						)
					)
				)
				(pin passive line
					(at 54.61 -81.28 180)
					(length 5.08) hide
					(name "VSS"
						(effects
							(font
								(size 1.27 1.27)
							)
						)
					)
					(number "T9"
						(effects
							(font
								(size 1.27 1.27)
							)
						)
					)
				)
				(pin passive line
					(at 0 -81.28 0)
					(length 5.08) hide
					(name "VSS_ANA"
						(effects
							(font
								(size 1.27 1.27)
							)
						)
					)
					(number "U22"
						(effects
							(font
								(size 1.27 1.27)
							)
						)
					)
				)
				(pin passive line
					(at 0 -81.28 0)
					(length 5.08) hide
					(name "VSS_ANA"
						(effects
							(font
								(size 1.27 1.27)
							)
						)
					)
					(number "U23"
						(effects
							(font
								(size 1.27 1.27)
							)
						)
					)
				)
				(pin power_in line
					(at 0 -5.08 0)
					(length 5.08)
					(name "VCC0P9_ANA_DPSNK"
						(effects
							(font
								(size 1.27 1.27)
							)
						)
					)
					(number "V11"
						(effects
							(font
								(size 1.27 1.27)
							)
						)
					)
				)
				(pin passive line
					(at 0 -5.08 0)
					(length 5.08) hide
					(name "VCC0P9_ANA_DPSNK"
						(effects
							(font
								(size 1.27 1.27)
							)
						)
					)
					(number "V12"
						(effects
							(font
								(size 1.27 1.27)
							)
						)
					)
				)
				(pin passive line
					(at 0 -5.08 0)
					(length 5.08) hide
					(name "VCC0P9_ANA_DPSNK"
						(effects
							(font
								(size 1.27 1.27)
							)
						)
					)
					(number "V13"
						(effects
							(font
								(size 1.27 1.27)
							)
						)
					)
				)
				(pin passive line
					(at 0 -81.28 0)
					(length 5.08) hide
					(name "VSS_ANA"
						(effects
							(font
								(size 1.27 1.27)
							)
						)
					)
					(number "V15"
						(effects
							(font
								(size 1.27 1.27)
							)
						)
					)
				)
				(pin passive line
					(at 0 -81.28 0)
					(length 5.08) hide
					(name "VSS_ANA"
						(effects
							(font
								(size 1.27 1.27)
							)
						)
					)
					(number "V16"
						(effects
							(font
								(size 1.27 1.27)
							)
						)
					)
				)
				(pin passive line
					(at 0 -81.28 0)
					(length 5.08) hide
					(name "VSS_ANA"
						(effects
							(font
								(size 1.27 1.27)
							)
						)
					)
					(number "V20"
						(effects
							(font
								(size 1.27 1.27)
							)
						)
					)
				)
				(pin passive line
					(at 0 -81.28 0)
					(length 5.08) hide
					(name "VSS_ANA"
						(effects
							(font
								(size 1.27 1.27)
							)
						)
					)
					(number "V5"
						(effects
							(font
								(size 1.27 1.27)
							)
						)
					)
				)
				(pin passive line
					(at 0 -81.28 0)
					(length 5.08) hide
					(name "VSS_ANA"
						(effects
							(font
								(size 1.27 1.27)
							)
						)
					)
					(number "V6"
						(effects
							(font
								(size 1.27 1.27)
							)
						)
					)
				)
				(pin passive line
					(at 0 -81.28 0)
					(length 5.08) hide
					(name "VSS_ANA"
						(effects
							(font
								(size 1.27 1.27)
							)
						)
					)
					(number "V8"
						(effects
							(font
								(size 1.27 1.27)
							)
						)
					)
				)
				(pin passive line
					(at 0 -81.28 0)
					(length 5.08) hide
					(name "VSS_ANA"
						(effects
							(font
								(size 1.27 1.27)
							)
						)
					)
					(number "V9"
						(effects
							(font
								(size 1.27 1.27)
							)
						)
					)
				)
				(pin passive line
					(at 0 -81.28 0)
					(length 5.08) hide
					(name "VSS_ANA"
						(effects
							(font
								(size 1.27 1.27)
							)
						)
					)
					(number "W20"
						(effects
							(font
								(size 1.27 1.27)
							)
						)
					)
				)
				(pin passive line
					(at 0 -81.28 0)
					(length 5.08) hide
					(name "VSS_ANA"
						(effects
							(font
								(size 1.27 1.27)
							)
						)
					)
					(number "W22"
						(effects
							(font
								(size 1.27 1.27)
							)
						)
					)
				)
				(pin passive line
					(at 0 -81.28 0)
					(length 5.08) hide
					(name "VSS_ANA"
						(effects
							(font
								(size 1.27 1.27)
							)
						)
					)
					(number "W23"
						(effects
							(font
								(size 1.27 1.27)
							)
						)
					)
				)
				(pin passive line
					(at 0 -81.28 0)
					(length 5.08) hide
					(name "VSS_ANA"
						(effects
							(font
								(size 1.27 1.27)
							)
						)
					)
					(number "W5"
						(effects
							(font
								(size 1.27 1.27)
							)
						)
					)
				)
				(pin passive line
					(at 0 -81.28 0)
					(length 5.08) hide
					(name "VSS_ANA"
						(effects
							(font
								(size 1.27 1.27)
							)
						)
					)
					(number "W6"
						(effects
							(font
								(size 1.27 1.27)
							)
						)
					)
				)
				(pin passive line
					(at 0 -81.28 0)
					(length 5.08) hide
					(name "VSS_ANA"
						(effects
							(font
								(size 1.27 1.27)
							)
						)
					)
					(number "W8"
						(effects
							(font
								(size 1.27 1.27)
							)
						)
					)
				)
				(pin passive line
					(at 0 -81.28 0)
					(length 5.08) hide
					(name "VSS_ANA"
						(effects
							(font
								(size 1.27 1.27)
							)
						)
					)
					(number "W9"
						(effects
							(font
								(size 1.27 1.27)
							)
						)
					)
				)
				(pin passive line
					(at 0 -81.28 0)
					(length 5.08) hide
					(name "VSS_ANA"
						(effects
							(font
								(size 1.27 1.27)
							)
						)
					)
					(number "Y13"
						(effects
							(font
								(size 1.27 1.27)
							)
						)
					)
				)
				(pin passive line
					(at 0 -81.28 0)
					(length 5.08) hide
					(name "VSS_ANA"
						(effects
							(font
								(size 1.27 1.27)
							)
						)
					)
					(number "Y20"
						(effects
							(font
								(size 1.27 1.27)
							)
						)
					)
				)
				(pin passive line
					(at 0 -81.28 0)
					(length 5.08) hide
					(name "VSS_ANA"
						(effects
							(font
								(size 1.27 1.27)
							)
						)
					)
					(number "Y9"
						(effects
							(font
								(size 1.27 1.27)
							)
						)
					)
				)
			)
			(symbol "JHL6340SLLSQ_2_0"
				(text "PCIe Gen3"
					(at 24.13 -17.78 0)
					(effects
						(font
							(size 1.27 1.27)
							(thickness 0.15)
						)
						(justify left bottom)
					)
				)
			)
			(symbol "JHL6340SLLSQ_2_1"
				(rectangle
					(start 5.08 5.08)
					(end 50.8 -40.64)
					(stroke
						(width 0.254)
						(type default)
					)
					(fill
						(type background)
					)
				)
				(pin output line
					(at 0 -38.1 0)
					(length 5.08)
					(name "PCIE_CLKREQ_N"
						(effects
							(font
								(size 1.27 1.27)
							)
						)
					)
					(number "AC5"
						(effects
							(font
								(size 1.27 1.27)
							)
						)
					)
				)
				(pin input line
					(at 55.88 -25.4 180)
					(length 5.08)
					(name "PCIE_TX3_N"
						(effects
							(font
								(size 1.27 1.27)
							)
						)
					)
					(number "F22"
						(effects
							(font
								(size 1.27 1.27)
							)
						)
					)
				)
				(pin input line
					(at 55.88 -22.86 180)
					(length 5.08)
					(name "PCIE_TX3_P"
						(effects
							(font
								(size 1.27 1.27)
							)
						)
					)
					(number "F23"
						(effects
							(font
								(size 1.27 1.27)
							)
						)
					)
				)
				(pin input line
					(at 0 -25.4 0)
					(length 5.08)
					(name "PCIE_RX3_N"
						(effects
							(font
								(size 1.27 1.27)
							)
						)
					)
					(number "H22"
						(effects
							(font
								(size 1.27 1.27)
							)
						)
					)
				)
				(pin input line
					(at 0 -22.86 0)
					(length 5.08)
					(name "PCIE_RX3_P"
						(effects
							(font
								(size 1.27 1.27)
							)
						)
					)
					(number "H23"
						(effects
							(font
								(size 1.27 1.27)
							)
						)
					)
				)
				(pin input line
					(at 55.88 -17.78 180)
					(length 5.08)
					(name "PCIE_TX2_N"
						(effects
							(font
								(size 1.27 1.27)
							)
						)
					)
					(number "K22"
						(effects
							(font
								(size 1.27 1.27)
							)
						)
					)
				)
				(pin input line
					(at 55.88 -15.24 180)
					(length 5.08)
					(name "PCIE_TX2_P"
						(effects
							(font
								(size 1.27 1.27)
							)
						)
					)
					(number "K23"
						(effects
							(font
								(size 1.27 1.27)
							)
						)
					)
				)
				(pin input line
					(at 55.88 -33.02 180)
					(length 5.08)
					(name "PERST_N"
						(effects
							(font
								(size 1.27 1.27)
							)
						)
					)
					(number "L4"
						(effects
							(font
								(size 1.27 1.27)
							)
						)
					)
				)
				(pin input line
					(at 0 -17.78 0)
					(length 5.08)
					(name "PCIE_RX2_N"
						(effects
							(font
								(size 1.27 1.27)
							)
						)
					)
					(number "M22"
						(effects
							(font
								(size 1.27 1.27)
							)
						)
					)
				)
				(pin input line
					(at 0 -15.24 0)
					(length 5.08)
					(name "PCIE_RX2_P"
						(effects
							(font
								(size 1.27 1.27)
							)
						)
					)
					(number "M23"
						(effects
							(font
								(size 1.27 1.27)
							)
						)
					)
				)
				(pin input line
					(at 55.88 -38.1 180)
					(length 5.08)
					(name "PCIE_RBIAS"
						(effects
							(font
								(size 1.27 1.27)
							)
						)
					)
					(number "N16"
						(effects
							(font
								(size 1.27 1.27)
							)
						)
					)
				)
				(pin input line
					(at 55.88 -10.16 180)
					(length 5.08)
					(name "PCIE_TX1_N"
						(effects
							(font
								(size 1.27 1.27)
							)
						)
					)
					(number "P22"
						(effects
							(font
								(size 1.27 1.27)
							)
						)
					)
				)
				(pin input line
					(at 55.88 -7.62 180)
					(length 5.08)
					(name "PCIE_TX1_P"
						(effects
							(font
								(size 1.27 1.27)
							)
						)
					)
					(number "P23"
						(effects
							(font
								(size 1.27 1.27)
							)
						)
					)
				)
				(pin input line
					(at 0 -33.02 0)
					(length 5.08)
					(name "PCIE_REFCLK_100_IN_N"
						(effects
							(font
								(size 1.27 1.27)
							)
						)
					)
					(number "T19"
						(effects
							(font
								(size 1.27 1.27)
							)
						)
					)
				)
				(pin input line
					(at 0 -10.16 0)
					(length 5.08)
					(name "PCIE_RX1_N"
						(effects
							(font
								(size 1.27 1.27)
							)
						)
					)
					(number "T22"
						(effects
							(font
								(size 1.27 1.27)
							)
						)
					)
				)
				(pin input line
					(at 0 -7.62 0)
					(length 5.08)
					(name "PCIE_RX1_P"
						(effects
							(font
								(size 1.27 1.27)
							)
						)
					)
					(number "T23"
						(effects
							(font
								(size 1.27 1.27)
							)
						)
					)
				)
				(pin input line
					(at 0 -30.48 0)
					(length 5.08)
					(name "PCIE_REFCLK_100_IN_P"
						(effects
							(font
								(size 1.27 1.27)
							)
						)
					)
					(number "V19"
						(effects
							(font
								(size 1.27 1.27)
							)
						)
					)
				)
				(pin input line
					(at 55.88 -2.54 180)
					(length 5.08)
					(name "PCIE_TX0_N"
						(effects
							(font
								(size 1.27 1.27)
							)
						)
					)
					(number "V22"
						(effects
							(font
								(size 1.27 1.27)
							)
						)
					)
				)
				(pin input line
					(at 55.88 0 180)
					(length 5.08)
					(name "PCIE_TX0_P"
						(effects
							(font
								(size 1.27 1.27)
							)
						)
					)
					(number "V23"
						(effects
							(font
								(size 1.27 1.27)
							)
						)
					)
				)
				(pin input line
					(at 0 -2.54 0)
					(length 5.08)
					(name "PCIE_RX0_N"
						(effects
							(font
								(size 1.27 1.27)
							)
						)
					)
					(number "Y22"
						(effects
							(font
								(size 1.27 1.27)
							)
						)
					)
				)
				(pin input line
					(at 0 0 0)
					(length 5.08)
					(name "PCIE_RX0_P"
						(effects
							(font
								(size 1.27 1.27)
							)
						)
					)
					(number "Y23"
						(effects
							(font
								(size 1.27 1.27)
							)
						)
					)
				)
			)
			(symbol "JHL6340SLLSQ_3_0"
				(polyline
					(pts
						(xy 15.24 -50.8) (xy 24.13 -50.8) (xy 24.13 -101.6) (xy 15.24 -101.6)
					)
					(stroke
						(width 0)
						(type default)
					)
					(fill
						(type none)
					)
				)
				(polyline
					(pts
						(xy 15.24 2.54) (xy 24.13 2.54) (xy 24.13 -48.26) (xy 15.24 -48.26)
					)
					(stroke
						(width 0)
						(type default)
					)
					(fill
						(type none)
					)
				)
				(polyline
					(pts
						(xy 40.64 -76.2) (xy 31.75 -76.2) (xy 31.75 -96.52) (xy 40.64 -96.52)
					)
					(stroke
						(width 0)
						(type default)
					)
					(fill
						(type none)
					)
				)
				(polyline
					(pts
						(xy 40.64 -48.26) (xy 31.75 -48.26) (xy 31.75 -73.66) (xy 40.64 -73.66)
					)
					(stroke
						(width 0)
						(type default)
					)
					(fill
						(type none)
					)
				)
				(polyline
					(pts
						(xy 40.64 2.54) (xy 31.75 2.54) (xy 31.75 -45.72) (xy 40.64 -45.72)
					)
					(stroke
						(width 0)
						(type default)
					)
					(fill
						(type none)
					)
				)
				(text "GPIO"
					(at 30.48 -60.96 900)
					(effects
						(font
							(size 1.27 1.27)
							(thickness 0.15)
						)
						(justify left bottom)
					)
				)
				(text "POC_GPIO"
					(at 30.48 -90.17 900)
					(effects
						(font
							(size 1.27 1.27)
							(thickness 0.15)
						)
						(justify left bottom)
					)
				)
				(text "SINK PORT 0"
					(at 26.67 -27.94 900)
					(effects
						(font
							(size 1.27 1.27)
							(thickness 0.15)
						)
						(justify left bottom)
					)
				)
				(text "SINK PORT 1"
					(at 26.67 -80.01 900)
					(effects
						(font
							(size 1.27 1.27)
							(thickness 0.15)
						)
						(justify left bottom)
					)
				)
				(text "SOURCE PORT 0"
					(at 30.48 -29.21 900)
					(effects
						(font
							(size 1.27 1.27)
							(thickness 0.15)
						)
						(justify left bottom)
					)
				)
			)
			(symbol "JHL6340SLLSQ_3_1"
				(rectangle
					(start 5.08 3.81)
					(end 50.8 -107.95)
					(stroke
						(width 0.254)
						(type default)
					)
					(fill
						(type background)
					)
				)
				(pin bidirectional line
					(at 55.88 -71.12 180)
					(length 5.08)
					(name "GPIO_8"
						(effects
							(font
								(size 1.27 1.27)
							)
						)
					)
					(number "AA1"
						(effects
							(font
								(size 1.27 1.27)
							)
						)
					)
				)
				(pin passive line
					(at 0 -38.1 0)
					(length 5.08)
					(name "DPSNK0_HPD"
						(effects
							(font
								(size 1.27 1.27)
							)
						)
					)
					(number "AA2"
						(effects
							(font
								(size 1.27 1.27)
							)
						)
					)
				)
				(pin input line
					(at 0 -15.24 0)
					(length 5.08)
					(name "DPSNK0_ML2_P"
						(effects
							(font
								(size 1.27 1.27)
							)
						)
					)
					(number "AB11"
						(effects
							(font
								(size 1.27 1.27)
							)
						)
					)
				)
				(pin input line
					(at 0 -22.86 0)
					(length 5.08)
					(name "DPSNK0_ML3_P"
						(effects
							(font
								(size 1.27 1.27)
							)
						)
					)
					(number "AB13"
						(effects
							(font
								(size 1.27 1.27)
							)
						)
					)
				)
				(pin input line
					(at 0 -53.34 0)
					(length 5.08)
					(name "DPSNK1_ML0_P"
						(effects
							(font
								(size 1.27 1.27)
							)
						)
					)
					(number "AB15"
						(effects
							(font
								(size 1.27 1.27)
							)
						)
					)
				)
				(pin input line
					(at 0 -60.96 0)
					(length 5.08)
					(name "DPSNK1_ML1_P"
						(effects
							(font
								(size 1.27 1.27)
							)
						)
					)
					(number "AB17"
						(effects
							(font
								(size 1.27 1.27)
							)
						)
					)
				)
				(pin input line
					(at 0 -68.58 0)
					(length 5.08)
					(name "DPSNK1_ML2_P"
						(effects
							(font
								(size 1.27 1.27)
							)
						)
					)
					(number "AB19"
						(effects
							(font
								(size 1.27 1.27)
							)
						)
					)
				)
				(pin input line
					(at 0 -76.2 0)
					(length 5.08)
					(name "DPSNK1_ML3_P"
						(effects
							(font
								(size 1.27 1.27)
							)
						)
					)
					(number "AB21"
						(effects
							(font
								(size 1.27 1.27)
							)
						)
					)
				)
				(pin input line
					(at 0 0 0)
					(length 5.08)
					(name "DPSNK0_ML0_P"
						(effects
							(font
								(size 1.27 1.27)
							)
						)
					)
					(number "AB7"
						(effects
							(font
								(size 1.27 1.27)
							)
						)
					)
				)
				(pin input line
					(at 0 -7.62 0)
					(length 5.08)
					(name "DPSNK0_ML1_P"
						(effects
							(font
								(size 1.27 1.27)
							)
						)
					)
					(number "AB9"
						(effects
							(font
								(size 1.27 1.27)
							)
						)
					)
				)
				(pin input line
					(at 0 -17.78 0)
					(length 5.08)
					(name "DPSNK0_ML2_N"
						(effects
							(font
								(size 1.27 1.27)
							)
						)
					)
					(number "AC11"
						(effects
							(font
								(size 1.27 1.27)
							)
						)
					)
				)
				(pin input line
					(at 0 -25.4 0)
					(length 5.08)
					(name "DPSNK0_ML3_N"
						(effects
							(font
								(size 1.27 1.27)
							)
						)
					)
					(number "AC13"
						(effects
							(font
								(size 1.27 1.27)
							)
						)
					)
				)
				(pin input line
					(at 0 -55.88 0)
					(length 5.08)
					(name "DPSNK1_ML0_N"
						(effects
							(font
								(size 1.27 1.27)
							)
						)
					)
					(number "AC15"
						(effects
							(font
								(size 1.27 1.27)
							)
						)
					)
				)
				(pin input line
					(at 0 -63.5 0)
					(length 5.08)
					(name "DPSNK1_ML1_N"
						(effects
							(font
								(size 1.27 1.27)
							)
						)
					)
					(number "AC17"
						(effects
							(font
								(size 1.27 1.27)
							)
						)
					)
				)
				(pin input line
					(at 0 -71.12 0)
					(length 5.08)
					(name "DPSNK1_ML2_N"
						(effects
							(font
								(size 1.27 1.27)
							)
						)
					)
					(number "AC19"
						(effects
							(font
								(size 1.27 1.27)
							)
						)
					)
				)
				(pin input line
					(at 0 -78.74 0)
					(length 5.08)
					(name "DPSNK1_ML3_N"
						(effects
							(font
								(size 1.27 1.27)
							)
						)
					)
					(number "AC21"
						(effects
							(font
								(size 1.27 1.27)
							)
						)
					)
				)
				(pin input line
					(at 0 -2.54 0)
					(length 5.08)
					(name "DPSNK0_ML0_N"
						(effects
							(font
								(size 1.27 1.27)
							)
						)
					)
					(number "AC7"
						(effects
							(font
								(size 1.27 1.27)
							)
						)
					)
				)
				(pin input line
					(at 0 -10.16 0)
					(length 5.08)
					(name "DPSNK0_ML1_N"
						(effects
							(font
								(size 1.27 1.27)
							)
						)
					)
					(number "AC9"
						(effects
							(font
								(size 1.27 1.27)
							)
						)
					)
				)
				(pin bidirectional line
					(at 55.88 -91.44 180)
					(length 5.08)
					(name "POC_GPIO_5"
						(effects
							(font
								(size 1.27 1.27)
							)
						)
					)
					(number "D2"
						(effects
							(font
								(size 1.27 1.27)
							)
						)
					)
				)
				(pin bidirectional line
					(at 55.88 -83.82 180)
					(length 5.08)
					(name "POC_GPIO_2"
						(effects
							(font
								(size 1.27 1.27)
							)
						)
					)
					(number "D4"
						(effects
							(font
								(size 1.27 1.27)
							)
						)
					)
				)
				(pin bidirectional line
					(at 55.88 -81.28 180)
					(length 5.08)
					(name "POC_GPIO_1"
						(effects
							(font
								(size 1.27 1.27)
							)
						)
					)
					(number "E2"
						(effects
							(font
								(size 1.27 1.27)
							)
						)
					)
				)
				(pin bidirectional line
					(at 55.88 -93.98 180)
					(length 5.08)
					(name "POC_GPIO_6"
						(effects
							(font
								(size 1.27 1.27)
							)
						)
					)
					(number "F1"
						(effects
							(font
								(size 1.27 1.27)
							)
						)
					)
				)
				(pin bidirectional line
					(at 55.88 -88.9 180)
					(length 5.08)
					(name "POC_GPIO_4"
						(effects
							(font
								(size 1.27 1.27)
							)
						)
					)
					(number "F2"
						(effects
							(font
								(size 1.27 1.27)
							)
						)
					)
				)
				(pin passive line
					(at 55.88 -38.1 180)
					(length 5.08)
					(name "DPSRC_HPD"
						(effects
							(font
								(size 1.27 1.27)
							)
						)
					)
					(number "G1"
						(effects
							(font
								(size 1.27 1.27)
							)
						)
					)
				)
				(pin bidirectional line
					(at 55.88 -86.36 180)
					(length 5.08)
					(name "POC_GPIO_3"
						(effects
							(font
								(size 1.27 1.27)
							)
						)
					)
					(number "H4"
						(effects
							(font
								(size 1.27 1.27)
							)
						)
					)
				)
				(pin output line
					(at 55.88 -25.4 180)
					(length 5.08)
					(name "DPSRC_ML3_N"
						(effects
							(font
								(size 1.27 1.27)
							)
						)
					)
					(number "J1"
						(effects
							(font
								(size 1.27 1.27)
							)
						)
					)
				)
				(pin output line
					(at 55.88 -22.86 180)
					(length 5.08)
					(name "DPSRC_ML3_P"
						(effects
							(font
								(size 1.27 1.27)
							)
						)
					)
					(number "J2"
						(effects
							(font
								(size 1.27 1.27)
							)
						)
					)
				)
				(pin bidirectional line
					(at 55.88 -78.74 180)
					(length 5.08)
					(name "POC_GPIO_0"
						(effects
							(font
								(size 1.27 1.27)
							)
						)
					)
					(number "J4"
						(effects
							(font
								(size 1.27 1.27)
							)
						)
					)
				)
				(pin output line
					(at 55.88 -17.78 180)
					(length 5.08)
					(name "DPSRC_ML2_N"
						(effects
							(font
								(size 1.27 1.27)
							)
						)
					)
					(number "L1"
						(effects
							(font
								(size 1.27 1.27)
							)
						)
					)
				)
				(pin output line
					(at 55.88 -15.24 180)
					(length 5.08)
					(name "DPSRC_ML2_P"
						(effects
							(font
								(size 1.27 1.27)
							)
						)
					)
					(number "L2"
						(effects
							(font
								(size 1.27 1.27)
							)
						)
					)
				)
				(pin output line
					(at 55.88 -10.16 180)
					(length 5.08)
					(name "DPSRC_ML1_N"
						(effects
							(font
								(size 1.27 1.27)
							)
						)
					)
					(number "N1"
						(effects
							(font
								(size 1.27 1.27)
							)
						)
					)
				)
				(pin output line
					(at 55.88 -7.62 180)
					(length 5.08)
					(name "DPSRC_ML1_P"
						(effects
							(font
								(size 1.27 1.27)
							)
						)
					)
					(number "N2"
						(effects
							(font
								(size 1.27 1.27)
							)
						)
					)
				)
				(pin passive line
					(at 0 -99.06 0)
					(length 5.08)
					(name "DPSNK1_DDC_DATA"
						(effects
							(font
								(size 1.27 1.27)
							)
						)
					)
					(number "N4"
						(effects
							(font
								(size 1.27 1.27)
							)
						)
					)
				)
				(pin passive line
					(at 55.88 -43.18 180)
					(length 5.08)
					(name "DPSRC_RBIAS"
						(effects
							(font
								(size 1.27 1.27)
							)
						)
					)
					(number "N6"
						(effects
							(font
								(size 1.27 1.27)
							)
						)
					)
				)
				(pin output line
					(at 55.88 -2.54 180)
					(length 5.08)
					(name "DPSRC_ML0_N"
						(effects
							(font
								(size 1.27 1.27)
							)
						)
					)
					(number "R1"
						(effects
							(font
								(size 1.27 1.27)
							)
						)
					)
				)
				(pin output line
					(at 55.88 0 180)
					(length 5.08)
					(name "DPSRC_ML0_P"
						(effects
							(font
								(size 1.27 1.27)
							)
						)
					)
					(number "R2"
						(effects
							(font
								(size 1.27 1.27)
							)
						)
					)
				)
				(pin passive line
					(at 0 -45.72 0)
					(length 5.08)
					(name "DPSNK0_DDC_DATA"
						(effects
							(font
								(size 1.27 1.27)
							)
						)
					)
					(number "R4"
						(effects
							(font
								(size 1.27 1.27)
							)
						)
					)
				)
				(pin bidirectional line
					(at 55.88 -50.8 180)
					(length 5.08)
					(name "GPIO_0"
						(effects
							(font
								(size 1.27 1.27)
							)
						)
					)
					(number "U1"
						(effects
							(font
								(size 1.27 1.27)
							)
						)
					)
				)
				(pin bidirectional line
					(at 55.88 -53.34 180)
					(length 5.08)
					(name "GPIO_1"
						(effects
							(font
								(size 1.27 1.27)
							)
						)
					)
					(number "U2"
						(effects
							(font
								(size 1.27 1.27)
							)
						)
					)
				)
				(pin bidirectional line
					(at 55.88 -55.88 180)
					(length 5.08)
					(name "GPIO_2"
						(effects
							(font
								(size 1.27 1.27)
							)
						)
					)
					(number "V1"
						(effects
							(font
								(size 1.27 1.27)
							)
						)
					)
				)
				(pin bidirectional line
					(at 55.88 -58.42 180)
					(length 5.08)
					(name "GPIO_3"
						(effects
							(font
								(size 1.27 1.27)
							)
						)
					)
					(number "V2"
						(effects
							(font
								(size 1.27 1.27)
							)
						)
					)
				)
				(pin bidirectional line
					(at 55.88 -60.96 180)
					(length 5.08)
					(name "GPIO_4"
						(effects
							(font
								(size 1.27 1.27)
							)
						)
					)
					(number "W1"
						(effects
							(font
								(size 1.27 1.27)
							)
						)
					)
				)
				(pin bidirectional line
					(at 0 -33.02 0)
					(length 5.08)
					(name "DPSNK0_AUX_N"
						(effects
							(font
								(size 1.27 1.27)
							)
						)
					)
					(number "W11"
						(effects
							(font
								(size 1.27 1.27)
							)
						)
					)
				)
				(pin bidirectional line
					(at 0 -86.36 0)
					(length 5.08)
					(name "DPSNK1_AUX_N"
						(effects
							(font
								(size 1.27 1.27)
							)
						)
					)
					(number "W12"
						(effects
							(font
								(size 1.27 1.27)
							)
						)
					)
				)
				(pin bidirectional line
					(at 55.88 -30.48 180)
					(length 5.08)
					(name "DPSRC_AUX_P"
						(effects
							(font
								(size 1.27 1.27)
							)
						)
					)
					(number "W19"
						(effects
							(font
								(size 1.27 1.27)
							)
						)
					)
				)
				(pin bidirectional line
					(at 55.88 -63.5 180)
					(length 5.08)
					(name "GPIO_5"
						(effects
							(font
								(size 1.27 1.27)
							)
						)
					)
					(number "W2"
						(effects
							(font
								(size 1.27 1.27)
							)
						)
					)
				)
				(pin bidirectional line
					(at 55.88 -66.04 180)
					(length 5.08)
					(name "GPIO_6"
						(effects
							(font
								(size 1.27 1.27)
							)
						)
					)
					(number "Y1"
						(effects
							(font
								(size 1.27 1.27)
							)
						)
					)
				)
				(pin bidirectional line
					(at 0 -30.48 0)
					(length 5.08)
					(name "DPSNK0_AUXP"
						(effects
							(font
								(size 1.27 1.27)
							)
						)
					)
					(number "Y11"
						(effects
							(font
								(size 1.27 1.27)
							)
						)
					)
				)
				(pin bidirectional line
					(at 0 -83.82 0)
					(length 5.08)
					(name "DPSNK1_AUXP"
						(effects
							(font
								(size 1.27 1.27)
							)
						)
					)
					(number "Y12"
						(effects
							(font
								(size 1.27 1.27)
							)
						)
					)
				)
				(pin passive line
					(at 0 -104.14 0)
					(length 5.08)
					(name "DPSNK_RBIAS"
						(effects
							(font
								(size 1.27 1.27)
							)
						)
					)
					(number "Y18"
						(effects
							(font
								(size 1.27 1.27)
							)
						)
					)
				)
				(pin bidirectional line
					(at 55.88 -33.02 180)
					(length 5.08)
					(name "DPSRC_AUX_N"
						(effects
							(font
								(size 1.27 1.27)
							)
						)
					)
					(number "Y19"
						(effects
							(font
								(size 1.27 1.27)
							)
						)
					)
				)
				(pin bidirectional line
					(at 55.88 -68.58 180)
					(length 5.08)
					(name "GPIO_7"
						(effects
							(font
								(size 1.27 1.27)
							)
						)
					)
					(number "Y2"
						(effects
							(font
								(size 1.27 1.27)
							)
						)
					)
				)
				(pin passive line
					(at 0 -43.18 0)
					(length 5.08)
					(name "DPSNK0_DDC_CLK"
						(effects
							(font
								(size 1.27 1.27)
							)
						)
					)
					(number "Y5"
						(effects
							(font
								(size 1.27 1.27)
							)
						)
					)
				)
				(pin passive line
					(at 0 -91.44 0)
					(length 5.08)
					(name "DPSNK1_HPD"
						(effects
							(font
								(size 1.27 1.27)
							)
						)
					)
					(number "Y6"
						(effects
							(font
								(size 1.27 1.27)
							)
						)
					)
				)
				(pin passive line
					(at 0 -96.52 0)
					(length 5.08)
					(name "DPSNK1_DDC_CLK"
						(effects
							(font
								(size 1.27 1.27)
							)
						)
					)
					(number "Y8"
						(effects
							(font
								(size 1.27 1.27)
							)
						)
					)
				)
			)
			(symbol "JHL6340SLLSQ_4_0"
				(text "MISCELLANEOUS"
					(at 20.32 -13.97 0)
					(effects
						(font
							(size 1.27 1.27)
							(thickness 0.15)
						)
						(justify left bottom)
					)
				)
			)
			(symbol "JHL6340SLLSQ_4_1"
				(rectangle
					(start 5.08 3.81)
					(end 50.8 -29.21)
					(stroke
						(width 0.254)
						(type default)
					)
					(fill
						(type background)
					)
				)
				(pin output line
					(at 55.88 -17.78 180)
					(length 5.08)
					(name "EE_DI"
						(effects
							(font
								(size 1.27 1.27)
							)
						)
					)
					(number "AB3"
						(effects
							(font
								(size 1.27 1.27)
							)
						)
					)
				)
				(pin output line
					(at 55.88 -25.4 180)
					(length 5.08)
					(name "EE_CLK"
						(effects
							(font
								(size 1.27 1.27)
							)
						)
					)
					(number "AB4"
						(effects
							(font
								(size 1.27 1.27)
							)
						)
					)
				)
				(pin input line
					(at 55.88 -2.54 180)
					(length 5.08)
					(name "TEST_PWR_GOOD"
						(effects
							(font
								(size 1.27 1.27)
							)
						)
					)
					(number "AB5"
						(effects
							(font
								(size 1.27 1.27)
							)
						)
					)
				)
				(pin output line
					(at 55.88 -22.86 180)
					(length 5.08)
					(name "EE_CS_N"
						(effects
							(font
								(size 1.27 1.27)
							)
						)
					)
					(number "AC3"
						(effects
							(font
								(size 1.27 1.27)
							)
						)
					)
				)
				(pin input line
					(at 55.88 -20.32 180)
					(length 5.08)
					(name "EE_D0"
						(effects
							(font
								(size 1.27 1.27)
							)
						)
					)
					(number "AC4"
						(effects
							(font
								(size 1.27 1.27)
							)
						)
					)
				)
				(pin input line
					(at 55.88 -10.16 180)
					(length 5.08)
					(name "XTAL_25_IN"
						(effects
							(font
								(size 1.27 1.27)
							)
						)
					)
					(number "D22"
						(effects
							(font
								(size 1.27 1.27)
							)
						)
					)
				)
				(pin input line
					(at 55.88 -12.7 180)
					(length 5.08)
					(name "XTAL_25_OUT"
						(effects
							(font
								(size 1.27 1.27)
							)
						)
					)
					(number "D23"
						(effects
							(font
								(size 1.27 1.27)
							)
						)
					)
				)
				(pin input line
					(at 55.88 0 180)
					(length 5.08)
					(name "TEST_EN"
						(effects
							(font
								(size 1.27 1.27)
							)
						)
					)
					(number "E1"
						(effects
							(font
								(size 1.27 1.27)
							)
						)
					)
				)
				(pin input line
					(at 55.88 -5.08 180)
					(length 5.08)
					(name "RESET_N"
						(effects
							(font
								(size 1.27 1.27)
							)
						)
					)
					(number "F4"
						(effects
							(font
								(size 1.27 1.27)
							)
						)
					)
				)
				(pin passive line
					(at 0 -12.7 0)
					(length 5.08)
					(name "RBIAS"
						(effects
							(font
								(size 1.27 1.27)
							)
						)
					)
					(number "H6"
						(effects
							(font
								(size 1.27 1.27)
							)
						)
					)
				)
				(pin passive line
					(at 0 -25.4 0)
					(length 5.08)
					(name "RSENSE"
						(effects
							(font
								(size 1.27 1.27)
							)
						)
					)
					(number "J6"
						(effects
							(font
								(size 1.27 1.27)
							)
						)
					)
				)
				(pin input line
					(at 0 -5.08 0)
					(length 5.08)
					(name "TCK"
						(effects
							(font
								(size 1.27 1.27)
							)
						)
					)
					(number "T4"
						(effects
							(font
								(size 1.27 1.27)
							)
						)
					)
				)
				(pin input line
					(at 0 -2.54 0)
					(length 5.08)
					(name "TMS"
						(effects
							(font
								(size 1.27 1.27)
							)
						)
					)
					(number "V4"
						(effects
							(font
								(size 1.27 1.27)
							)
						)
					)
				)
				(pin output line
					(at 0 -7.62 0)
					(length 5.08)
					(name "TDO"
						(effects
							(font
								(size 1.27 1.27)
							)
						)
					)
					(number "W4"
						(effects
							(font
								(size 1.27 1.27)
							)
						)
					)
				)
				(pin input line
					(at 0 0 0)
					(length 5.08)
					(name "TDI"
						(effects
							(font
								(size 1.27 1.27)
							)
						)
					)
					(number "Y4"
						(effects
							(font
								(size 1.27 1.27)
							)
						)
					)
				)
			)
			(symbol "JHL6340SLLSQ_5_0"
				(polyline
					(pts
						(xy 15.24 2.54) (xy 24.13 2.54) (xy 24.13 -58.42) (xy 13.97 -58.42)
					)
					(stroke
						(width 0)
						(type default)
					)
					(fill
						(type none)
					)
				)
				(polyline
					(pts
						(xy 40.64 2.54) (xy 31.75 2.54) (xy 31.75 -58.42) (xy 41.91 -58.42)
					)
					(stroke
						(width 0)
						(type default)
					)
					(fill
						(type none)
					)
				)
				(text "TBT PORT A"
					(at 26.67 -31.75 900)
					(effects
						(font
							(size 1.27 1.27)
							(thickness 0.15)
						)
						(justify left bottom)
					)
				)
				(text "TBT PORT B"
					(at 31.115 -31.75 900)
					(effects
						(font
							(size 1.27 1.27)
							(thickness 0.15)
						)
						(justify left bottom)
					)
				)
			)
			(symbol "JHL6340SLLSQ_5_1"
				(rectangle
					(start 5.08 3.81)
					(end 50.8 -59.69)
					(stroke
						(width 0.254)
						(type default)
					)
					(fill
						(type background)
					)
				)
				(pin output line
					(at 55.88 -15.24 180)
					(length 5.08)
					(name "PB_TX0_P"
						(effects
							(font
								(size 1.27 1.27)
							)
						)
					)
					(number "A11"
						(effects
							(font
								(size 1.27 1.27)
							)
						)
					)
				)
				(pin input line
					(at 55.88 0 180)
					(length 5.08)
					(name "PB_RX0_P"
						(effects
							(font
								(size 1.27 1.27)
							)
						)
					)
					(number "A13"
						(effects
							(font
								(size 1.27 1.27)
							)
						)
					)
				)
				(pin input line
					(at 0 -7.62 0)
					(length 5.08)
					(name "PA_RX1_P"
						(effects
							(font
								(size 1.27 1.27)
							)
						)
					)
					(number "A15"
						(effects
							(font
								(size 1.27 1.27)
							)
						)
					)
				)
				(pin output line
					(at 0 -22.86 0)
					(length 5.08)
					(name "PA_TX1_P"
						(effects
							(font
								(size 1.27 1.27)
							)
						)
					)
					(number "A17"
						(effects
							(font
								(size 1.27 1.27)
							)
						)
					)
				)
				(pin output line
					(at 0 -15.24 0)
					(length 5.08)
					(name "PA_TX0_P"
						(effects
							(font
								(size 1.27 1.27)
							)
						)
					)
					(number "A19"
						(effects
							(font
								(size 1.27 1.27)
							)
						)
					)
				)
				(pin input line
					(at 0 -2.54 0)
					(length 5.08)
					(name "PA_RX0_N"
						(effects
							(font
								(size 1.27 1.27)
							)
						)
					)
					(number "A21"
						(effects
							(font
								(size 1.27 1.27)
							)
						)
					)
				)
				(pin input line
					(at 0 -48.26 0)
					(length 5.08)
					(name "PA_LSRX"
						(effects
							(font
								(size 1.27 1.27)
							)
						)
					)
					(number "A4"
						(effects
							(font
								(size 1.27 1.27)
							)
						)
					)
				)
				(pin output line
					(at 0 -45.72 0)
					(length 5.08)
					(name "PA_LSTX"
						(effects
							(font
								(size 1.27 1.27)
							)
						)
					)
					(number "A5"
						(effects
							(font
								(size 1.27 1.27)
							)
						)
					)
				)
				(pin input line
					(at 55.88 -10.16 180)
					(length 5.08)
					(name "PB_RX1_N"
						(effects
							(font
								(size 1.27 1.27)
							)
						)
					)
					(number "A7"
						(effects
							(font
								(size 1.27 1.27)
							)
						)
					)
				)
				(pin output line
					(at 55.88 -22.86 180)
					(length 5.08)
					(name "PB_TX1_P"
						(effects
							(font
								(size 1.27 1.27)
							)
						)
					)
					(number "A9"
						(effects
							(font
								(size 1.27 1.27)
							)
						)
					)
				)
				(pin output line
					(at 55.88 -17.78 180)
					(length 5.08)
					(name "PB_TX0_N"
						(effects
							(font
								(size 1.27 1.27)
							)
						)
					)
					(number "B11"
						(effects
							(font
								(size 1.27 1.27)
							)
						)
					)
				)
				(pin input line
					(at 55.88 -2.54 180)
					(length 5.08)
					(name "PB_RX0_N"
						(effects
							(font
								(size 1.27 1.27)
							)
						)
					)
					(number "B13"
						(effects
							(font
								(size 1.27 1.27)
							)
						)
					)
				)
				(pin input line
					(at 0 -10.16 0)
					(length 5.08)
					(name "PA_RX1_N"
						(effects
							(font
								(size 1.27 1.27)
							)
						)
					)
					(number "B15"
						(effects
							(font
								(size 1.27 1.27)
							)
						)
					)
				)
				(pin output line
					(at 0 -25.4 0)
					(length 5.08)
					(name "PA_TX1_N"
						(effects
							(font
								(size 1.27 1.27)
							)
						)
					)
					(number "B17"
						(effects
							(font
								(size 1.27 1.27)
							)
						)
					)
				)
				(pin output line
					(at 0 -17.78 0)
					(length 5.08)
					(name "PA_TX0_N"
						(effects
							(font
								(size 1.27 1.27)
							)
						)
					)
					(number "B19"
						(effects
							(font
								(size 1.27 1.27)
							)
						)
					)
				)
				(pin input line
					(at 0 0 0)
					(length 5.08)
					(name "PA_RX0_P"
						(effects
							(font
								(size 1.27 1.27)
							)
						)
					)
					(number "B21"
						(effects
							(font
								(size 1.27 1.27)
							)
						)
					)
				)
				(pin output line
					(at 55.88 -45.72 180)
					(length 5.08)
					(name "PB_LSTX"
						(effects
							(font
								(size 1.27 1.27)
							)
						)
					)
					(number "B4"
						(effects
							(font
								(size 1.27 1.27)
							)
						)
					)
				)
				(pin input line
					(at 55.88 -48.26 180)
					(length 5.08)
					(name "PB_LSRX"
						(effects
							(font
								(size 1.27 1.27)
							)
						)
					)
					(number "B5"
						(effects
							(font
								(size 1.27 1.27)
							)
						)
					)
				)
				(pin input line
					(at 55.88 -7.62 180)
					(length 5.08)
					(name "PB_RX1_P"
						(effects
							(font
								(size 1.27 1.27)
							)
						)
					)
					(number "B7"
						(effects
							(font
								(size 1.27 1.27)
							)
						)
					)
				)
				(pin output line
					(at 55.88 -25.4 180)
					(length 5.08)
					(name "PB_TX1_N"
						(effects
							(font
								(size 1.27 1.27)
							)
						)
					)
					(number "B9"
						(effects
							(font
								(size 1.27 1.27)
							)
						)
					)
				)
				(pin bidirectional line
					(at 55.88 -40.64 180)
					(length 5.08)
					(name "PB_USB2_D_N"
						(effects
							(font
								(size 1.27 1.27)
							)
						)
					)
					(number "D19"
						(effects
							(font
								(size 1.27 1.27)
							)
						)
					)
				)
				(pin bidirectional line
					(at 0 -40.64 0)
					(length 5.08)
					(name "PA_USB2_D_N"
						(effects
							(font
								(size 1.27 1.27)
							)
						)
					)
					(number "D20"
						(effects
							(font
								(size 1.27 1.27)
							)
						)
					)
				)
				(pin bidirectional line
					(at 55.88 -38.1 180)
					(length 5.08)
					(name "PB_USB2_D_P"
						(effects
							(font
								(size 1.27 1.27)
							)
						)
					)
					(number "E19"
						(effects
							(font
								(size 1.27 1.27)
							)
						)
					)
				)
				(pin bidirectional line
					(at 0 -38.1 0)
					(length 5.08)
					(name "PA_USB2_D_P"
						(effects
							(font
								(size 1.27 1.27)
							)
						)
					)
					(number "E20"
						(effects
							(font
								(size 1.27 1.27)
							)
						)
					)
				)
				(pin passive line
					(at 55.88 -55.88 180)
					(length 5.08)
					(name "PB_USB2_RBIAS"
						(effects
							(font
								(size 1.27 1.27)
							)
						)
					)
					(number "F19"
						(effects
							(font
								(size 1.27 1.27)
							)
						)
					)
				)
				(pin input line
					(at 55.88 -50.8 180)
					(length 5.08)
					(name "PB_DPSRC_HPD"
						(effects
							(font
								(size 1.27 1.27)
							)
						)
					)
					(number "G2"
						(effects
							(font
								(size 1.27 1.27)
							)
						)
					)
				)
				(pin passive line
					(at 0 -55.88 0)
					(length 5.08)
					(name "PA_USB2_RBIAS"
						(effects
							(font
								(size 1.27 1.27)
							)
						)
					)
					(number "H19"
						(effects
							(font
								(size 1.27 1.27)
							)
						)
					)
				)
				(pin input line
					(at 0 -50.8 0)
					(length 5.08)
					(name "PA_DPSRC_HPD"
						(effects
							(font
								(size 1.27 1.27)
							)
						)
					)
					(number "M4"
						(effects
							(font
								(size 1.27 1.27)
							)
						)
					)
				)
				(pin bidirectional line
					(at 0 -33.02 0)
					(length 5.08)
					(name "PA_DPSRC_AUX_N"
						(effects
							(font
								(size 1.27 1.27)
							)
						)
					)
					(number "W15"
						(effects
							(font
								(size 1.27 1.27)
							)
						)
					)
				)
				(pin bidirectional line
					(at 55.88 -33.02 180)
					(length 5.08)
					(name "PB_DPSRC_AUX_N"
						(effects
							(font
								(size 1.27 1.27)
							)
						)
					)
					(number "W16"
						(effects
							(font
								(size 1.27 1.27)
							)
						)
					)
				)
				(pin bidirectional line
					(at 0 -30.48 0)
					(length 5.08)
					(name "PA_DPSRC_AUX_P"
						(effects
							(font
								(size 1.27 1.27)
							)
						)
					)
					(number "Y15"
						(effects
							(font
								(size 1.27 1.27)
							)
						)
					)
				)
				(pin bidirectional line
					(at 55.88 -30.48 180)
					(length 5.08)
					(name "PB_DPSRC_AUX_P"
						(effects
							(font
								(size 1.27 1.27)
							)
						)
					)
					(number "Y16"
						(effects
							(font
								(size 1.27 1.27)
							)
						)
					)
				)
			)
			(symbol "JHL6340SLLSQ_6_0"
				(text "DEBUG"
					(at 24.13 -15.24 0)
					(effects
						(font
							(size 1.27 1.27)
							(thickness 0.15)
						)
						(justify left bottom)
					)
				)
			)
			(symbol "JHL6340SLLSQ_6_1"
				(rectangle
					(start 5.08 3.81)
					(end 50.8 -31.75)
					(stroke
						(width 0.254)
						(type default)
					)
					(fill
						(type background)
					)
				)
				(pin passive line
					(at 55.88 -5.08 180)
					(length 5.08)
					(name "ATEST_P"
						(effects
							(font
								(size 1.27 1.27)
							)
						)
					)
					(number "A23"
						(effects
							(font
								(size 1.27 1.27)
							)
						)
					)
				)
				(pin passive line
					(at 55.88 -25.4 180)
					(length 5.08)
					(name "MONDC_DPSRC"
						(effects
							(font
								(size 1.27 1.27)
							)
						)
					)
					(number "AB2"
						(effects
							(font
								(size 1.27 1.27)
							)
						)
					)
				)
				(pin passive line
					(at 0 0 0)
					(length 5.08)
					(name "THERMDA2"
						(effects
							(font
								(size 1.27 1.27)
							)
						)
					)
					(number "AB23"
						(effects
							(font
								(size 1.27 1.27)
							)
						)
					)
				)
				(pin passive line
					(at 0 -12.7 0)
					(length 5.08)
					(name "TEST_EDM"
						(effects
							(font
								(size 1.27 1.27)
							)
						)
					)
					(number "AC1"
						(effects
							(font
								(size 1.27 1.27)
							)
						)
					)
				)
				(pin passive line
					(at 0 -2.54 0)
					(length 5.08)
					(name "THERMDA1"
						(effects
							(font
								(size 1.27 1.27)
							)
						)
					)
					(number "AC23"
						(effects
							(font
								(size 1.27 1.27)
							)
						)
					)
				)
				(pin passive line
					(at 55.88 -7.62 180)
					(length 5.08)
					(name "ATEST_N"
						(effects
							(font
								(size 1.27 1.27)
							)
						)
					)
					(number "B23"
						(effects
							(font
								(size 1.27 1.27)
							)
						)
					)
				)
				(pin passive line
					(at 0 -27.94 0)
					(length 5.08)
					(name "MONDC_CIO_1"
						(effects
							(font
								(size 1.27 1.27)
							)
						)
					)
					(number "C22"
						(effects
							(font
								(size 1.27 1.27)
							)
						)
					)
				)
				(pin passive line
					(at 0 -25.4 0)
					(length 5.08)
					(name "MONDC_CIO_0"
						(effects
							(font
								(size 1.27 1.27)
							)
						)
					)
					(number "C23"
						(effects
							(font
								(size 1.27 1.27)
							)
						)
					)
				)
				(pin passive line
					(at 55.88 0 180)
					(length 5.08)
					(name "MONDC_SVR"
						(effects
							(font
								(size 1.27 1.27)
							)
						)
					)
					(number "D6"
						(effects
							(font
								(size 1.27 1.27)
							)
						)
					)
				)
				(pin passive line
					(at 55.88 -12.7 180)
					(length 5.08)
					(name "USB2_ATEST"
						(effects
							(font
								(size 1.27 1.27)
							)
						)
					)
					(number "E18"
						(effects
							(font
								(size 1.27 1.27)
							)
						)
					)
				)
				(pin passive line
					(at 0 -17.78 0)
					(length 5.08)
					(name "FUSE_VQPS_64"
						(effects
							(font
								(size 1.27 1.27)
							)
						)
					)
					(number "L15"
						(effects
							(font
								(size 1.27 1.27)
							)
						)
					)
				)
				(pin passive line
					(at 0 -20.32 0)
					(length 5.08)
					(name "FUSE_VQPS_128"
						(effects
							(font
								(size 1.27 1.27)
							)
						)
					)
					(number "N15"
						(effects
							(font
								(size 1.27 1.27)
							)
						)
					)
				)
				(pin passive line
					(at 0 -7.62 0)
					(length 5.08)
					(name "PCIE_ATEST"
						(effects
							(font
								(size 1.27 1.27)
							)
						)
					)
					(number "V18"
						(effects
							(font
								(size 1.27 1.27)
							)
						)
					)
				)
				(pin passive line
					(at 55.88 -17.78 180)
					(length 5.08)
					(name "MONDC_DPSNK_0"
						(effects
							(font
								(size 1.27 1.27)
							)
						)
					)
					(number "W13"
						(effects
							(font
								(size 1.27 1.27)
							)
						)
					)
				)
				(pin passive line
					(at 55.88 -20.32 180)
					(length 5.08)
					(name "MONDC_DPSNK_1"
						(effects
							(font
								(size 1.27 1.27)
							)
						)
					)
					(number "W18"
						(effects
							(font
								(size 1.27 1.27)
							)
						)
					)
				)
			)
		)
	(symbol "antmicroInterfaceControllers:TPS65983BAZBHR"
			(exclude_from_sim no)
			(in_bom yes)
			(on_board yes)
			(property "Reference" "U"
				(at 73.66 2.54 0)
				(effects
					(font
						(size 1.27 1.27)
						(thickness 0.15)
					)
					(justify left bottom)
				)
			)
			(property "Value" "TPS65983BAZBHR"
				(at 73.66 0 0)
				(effects
					(font
						(size 1.27 1.27)
						(thickness 0.15)
					)
					(justify left bottom)
					(hide yes)
				)
			)
			(property "Footprint" "antmicro-footprints:IC_TPS65983BAZBHR"
				(at 73.66 -2.54 0)
				(effects
					(font
						(size 1.27 1.27)
						(thickness 0.15)
					)
					(justify left bottom)
					(hide yes)
				)
			)
			(property "Datasheet" "https://www.ti.com/lit/ds/symlink/tps65983b.pdf?ts=1678712702533&ref_url=https%253A%252F%252Fwww.ti.com%252Fproduct%252FTPS65983B"
				(at 73.66 -5.08 0)
				(effects
					(font
						(size 1.27 1.27)
						(thickness 0.15)
					)
					(justify left bottom)
					(hide yes)
				)
			)
			(property "Description" "USB Interface IC Universal USB Type-C and Power Delivery (PD) 3.0 controller 96-NFBGA -10°C to 85"
				(at 0 0 0)
				(effects
					(font
						(size 1.27 1.27)
					)
					(hide yes)
				)
			)
			(property "MPN" "TPS65983BAZBHR"
				(at 73.66 -7.62 0)
				(effects
					(font
						(size 1.27 1.27)
						(thickness 0.15)
					)
					(justify left bottom)
				)
			)
			(property "Manufacturer" "Texas Instruments"
				(at 73.66 -10.16 0)
				(effects
					(font
						(size 1.27 1.27)
						(thickness 0.15)
					)
					(justify left bottom)
					(hide yes)
				)
			)
			(property "Author" "Antmicro"
				(at 73.66 -12.7 0)
				(effects
					(font
						(size 1.27 1.27)
						(thickness 0.15)
					)
					(justify left bottom)
					(hide yes)
				)
			)
			(property "License" "Apache-2.0"
				(at 73.66 -15.24 0)
				(effects
					(font
						(size 1.27 1.27)
						(thickness 0.15)
					)
					(justify left bottom)
					(hide yes)
				)
			)
			(property "ki_keywords" "IC"
				(at 0 0 0)
				(effects
					(font
						(size 1.27 1.27)
					)
					(hide yes)
				)
			)
			(symbol "TPS65983BAZBHR_0_1"
				(rectangle
					(start 3.81 5.08)
					(end 54.61 -129.54)
					(stroke
						(width 0)
						(type default)
					)
					(fill
						(type background)
					)
				)
			)
			(symbol "TPS65983BAZBHR_1_1"
				(pin power_in line
					(at 0 -127 0)
					(length 3.81)
					(name "GND"
						(effects
							(font
								(size 1.27 1.27)
							)
						)
					)
					(number "A1"
						(effects
							(font
								(size 1.27 1.27)
							)
						)
					)
				)
				(pin input line
					(at 0 0 0)
					(length 3.81)
					(name "SENSEN"
						(effects
							(font
								(size 1.27 1.27)
							)
						)
					)
					(number "A10"
						(effects
							(font
								(size 1.27 1.27)
							)
						)
					)
				)
				(pin power_in line
					(at 0 -10.16 0)
					(length 3.81)
					(name "PP_5V0"
						(effects
							(font
								(size 1.27 1.27)
							)
						)
					)
					(number "A11"
						(effects
							(font
								(size 1.27 1.27)
							)
						)
					)
				)
				(pin power_out line
					(at 58.42 -22.86 180)
					(length 3.81)
					(name "LDO_1V8D"
						(effects
							(font
								(size 1.27 1.27)
							)
						)
					)
					(number "A2"
						(effects
							(font
								(size 1.27 1.27)
							)
						)
					)
				)
				(pin output line
					(at 0 -76.2 0)
					(length 3.81)
					(name "SPI_CLK"
						(effects
							(font
								(size 1.27 1.27)
							)
						)
					)
					(number "A3"
						(effects
							(font
								(size 1.27 1.27)
							)
						)
					)
				)
				(pin input line
					(at 0 -81.28 0)
					(length 3.81)
					(name "SPI_POCI"
						(effects
							(font
								(size 1.27 1.27)
							)
						)
					)
					(number "A4"
						(effects
							(font
								(size 1.27 1.27)
							)
						)
					)
				)
				(pin bidirectional line
					(at 0 -40.64 0)
					(length 3.81)
					(name "I2C_SDA2"
						(effects
							(font
								(size 1.27 1.27)
							)
						)
					)
					(number "A5"
						(effects
							(font
								(size 1.27 1.27)
							)
						)
					)
				)
				(pin power_in line
					(at 0 -5.08 0)
					(length 3.81)
					(name "PP_HV"
						(effects
							(font
								(size 1.27 1.27)
							)
						)
					)
					(number "A6"
						(effects
							(font
								(size 1.27 1.27)
							)
						)
					)
				)
				(pin power_in line
					(at 0 -5.08 0)
					(length 3.81) hide
					(name "PP_HV"
						(effects
							(font
								(size 1.27 1.27)
							)
						)
					)
					(number "A7"
						(effects
							(font
								(size 1.27 1.27)
							)
						)
					)
				)
				(pin power_in line
					(at 0 -5.08 0)
					(length 3.81) hide
					(name "PP_HV"
						(effects
							(font
								(size 1.27 1.27)
							)
						)
					)
					(number "A8"
						(effects
							(font
								(size 1.27 1.27)
							)
						)
					)
				)
				(pin output line
					(at 58.42 0 180)
					(length 3.81)
					(name "HV_GATE2"
						(effects
							(font
								(size 1.27 1.27)
							)
						)
					)
					(number "A9"
						(effects
							(font
								(size 1.27 1.27)
							)
						)
					)
				)
				(pin power_in line
					(at 0 -20.32 0)
					(length 3.81)
					(name "VDDIO"
						(effects
							(font
								(size 1.27 1.27)
							)
						)
					)
					(number "B1"
						(effects
							(font
								(size 1.27 1.27)
							)
						)
					)
				)
				(pin input line
					(at 0 2.54 0)
					(length 3.81)
					(name "SENSEP"
						(effects
							(font
								(size 1.27 1.27)
							)
						)
					)
					(number "B10"
						(effects
							(font
								(size 1.27 1.27)
							)
						)
					)
				)
				(pin power_in line
					(at 0 -10.16 0)
					(length 3.81) hide
					(name "PP_5V0"
						(effects
							(font
								(size 1.27 1.27)
							)
						)
					)
					(number "B11"
						(effects
							(font
								(size 1.27 1.27)
							)
						)
					)
				)
				(pin bidirectional line
					(at 0 -50.8 0)
					(length 3.81)
					(name "GPIO0(HD3_AMSEL)"
						(effects
							(font
								(size 1.27 1.27)
							)
						)
					)
					(number "B2"
						(effects
							(font
								(size 1.27 1.27)
							)
						)
					)
				)
				(pin output line
					(at 0 -83.82 0)
					(length 3.81)
					(name "SPI_CSZ"
						(effects
							(font
								(size 1.27 1.27)
							)
						)
					)
					(number "B3"
						(effects
							(font
								(size 1.27 1.27)
							)
						)
					)
				)
				(pin output line
					(at 0 -78.74 0)
					(length 3.81)
					(name "SPI_PICO"
						(effects
							(font
								(size 1.27 1.27)
							)
						)
					)
					(number "B4"
						(effects
							(font
								(size 1.27 1.27)
							)
						)
					)
				)
				(pin bidirectional line
					(at 0 -43.18 0)
					(length 3.81)
					(name "I2C_SCL2"
						(effects
							(font
								(size 1.27 1.27)
							)
						)
					)
					(number "B5"
						(effects
							(font
								(size 1.27 1.27)
							)
						)
					)
				)
				(pin output line
					(at 0 -45.72 0)
					(length 3.81)
					(name "I2C_IRQ2Z"
						(effects
							(font
								(size 1.27 1.27)
							)
						)
					)
					(number "B6"
						(effects
							(font
								(size 1.27 1.27)
							)
						)
					)
				)
				(pin power_in line
					(at 0 -5.08 0)
					(length 3.81) hide
					(name "PP_HV"
						(effects
							(font
								(size 1.27 1.27)
							)
						)
					)
					(number "B7"
						(effects
							(font
								(size 1.27 1.27)
							)
						)
					)
				)
				(pin power_in line
					(at 0 -127 0)
					(length 3.81) hide
					(name "GND"
						(effects
							(font
								(size 1.27 1.27)
							)
						)
					)
					(number "B8"
						(effects
							(font
								(size 1.27 1.27)
							)
						)
					)
				)
				(pin output line
					(at 58.42 2.54 180)
					(length 3.81)
					(name "HV_GATE1"
						(effects
							(font
								(size 1.27 1.27)
							)
						)
					)
					(number "B9"
						(effects
							(font
								(size 1.27 1.27)
							)
						)
					)
				)
				(pin output line
					(at 0 -35.56 0)
					(length 3.81)
					(name "I2C_IRQ1Z"
						(effects
							(font
								(size 1.27 1.27)
							)
						)
					)
					(number "C1"
						(effects
							(font
								(size 1.27 1.27)
							)
						)
					)
				)
				(pin bidirectional line
					(at 0 -60.96 0)
					(length 3.81)
					(name "GPIO4(HPD_TXRX)"
						(effects
							(font
								(size 1.27 1.27)
							)
						)
					)
					(number "C10"
						(effects
							(font
								(size 1.27 1.27)
							)
						)
					)
				)
				(pin power_in line
					(at 0 -10.16 0)
					(length 3.81) hide
					(name "PP_5V0"
						(effects
							(font
								(size 1.27 1.27)
							)
						)
					)
					(number "C11"
						(effects
							(font
								(size 1.27 1.27)
							)
						)
					)
				)
				(pin bidirectional line
					(at 0 -53.34 0)
					(length 3.81)
					(name "GPIO1(CONFIG0)"
						(effects
							(font
								(size 1.27 1.27)
							)
						)
					)
					(number "C2"
						(effects
							(font
								(size 1.27 1.27)
							)
						)
					)
				)
				(pin bidirectional line
					(at 0 -30.48 0)
					(length 3.81)
					(name "I2C_SDA1"
						(effects
							(font
								(size 1.27 1.27)
							)
						)
					)
					(number "D1"
						(effects
							(font
								(size 1.27 1.27)
							)
						)
					)
				)
				(pin bidirectional line
					(at 0 -55.88 0)
					(length 3.81)
					(name "GPIO2"
						(effects
							(font
								(size 1.27 1.27)
							)
						)
					)
					(number "D10"
						(effects
							(font
								(size 1.27 1.27)
							)
						)
					)
				)
				(pin power_in line
					(at 0 -10.16 0)
					(length 3.81) hide
					(name "PP_5V0"
						(effects
							(font
								(size 1.27 1.27)
							)
						)
					)
					(number "D11"
						(effects
							(font
								(size 1.27 1.27)
							)
						)
					)
				)
				(pin bidirectional line
					(at 0 -33.02 0)
					(length 3.81)
					(name "I2C_SCL1"
						(effects
							(font
								(size 1.27 1.27)
							)
						)
					)
					(number "D2"
						(effects
							(font
								(size 1.27 1.27)
							)
						)
					)
				)
				(pin bidirectional line
					(at 58.42 -83.82 180)
					(length 3.81)
					(name "DEBUG_CTL2(GPIO17,_I2CADDR_B5)"
						(effects
							(font
								(size 1.27 1.27)
							)
						)
					)
					(number "D5"
						(effects
							(font
								(size 1.27 1.27)
							)
						)
					)
				)
				(pin input line
					(at 58.42 -106.68 180)
					(length 3.81)
					(name "HRESET"
						(effects
							(font
								(size 1.27 1.27)
							)
						)
					)
					(number "D6"
						(effects
							(font
								(size 1.27 1.27)
							)
						)
					)
				)
				(pin bidirectional line
					(at 0 -68.58 0)
					(length 3.81)
					(name "GPIO7"
						(effects
							(font
								(size 1.27 1.27)
							)
						)
					)
					(number "D7"
						(effects
							(font
								(size 1.27 1.27)
							)
						)
					)
				)
				(pin power_in line
					(at 0 -127 0)
					(length 3.81) hide
					(name "GND"
						(effects
							(font
								(size 1.27 1.27)
							)
						)
					)
					(number "D8"
						(effects
							(font
								(size 1.27 1.27)
							)
						)
					)
				)
				(pin power_out line
					(at 58.42 -27.94 180)
					(length 3.81)
					(name "LDO_BMC"
						(effects
							(font
								(size 1.27 1.27)
							)
						)
					)
					(number "E1"
						(effects
							(font
								(size 1.27 1.27)
							)
						)
					)
				)
				(pin bidirectional line
					(at 0 -63.5 0)
					(length 3.81)
					(name "GPIO5(HPD_RX)"
						(effects
							(font
								(size 1.27 1.27)
							)
						)
					)
					(number "E10"
						(effects
							(font
								(size 1.27 1.27)
							)
						)
					)
				)
				(pin bidirectional line
					(at 58.42 -101.6 180)
					(length 3.81)
					(name "MRESET(GPIO11)"
						(effects
							(font
								(size 1.27 1.27)
							)
						)
					)
					(number "E11"
						(effects
							(font
								(size 1.27 1.27)
							)
						)
					)
				)
				(pin output line
					(at 0 -99.06 0)
					(length 3.81)
					(name "UART_TX"
						(effects
							(font
								(size 1.27 1.27)
							)
						)
					)
					(number "E2"
						(effects
							(font
								(size 1.27 1.27)
							)
						)
					)
				)
				(pin bidirectional line
					(at 58.42 -86.36 180)
					(length 3.81)
					(name "DEBUG_CTL1(GPIO16,_I2CADDR_B4)"
						(effects
							(font
								(size 1.27 1.27)
							)
						)
					)
					(number "E4"
						(effects
							(font
								(size 1.27 1.27)
							)
						)
					)
				)
				(pin power_in line
					(at 0 -127 0)
					(length 3.81) hide
					(name "GND"
						(effects
							(font
								(size 1.27 1.27)
							)
						)
					)
					(number "E5"
						(effects
							(font
								(size 1.27 1.27)
							)
						)
					)
				)
				(pin power_in line
					(at 0 -127 0)
					(length 3.81) hide
					(name "GND"
						(effects
							(font
								(size 1.27 1.27)
							)
						)
					)
					(number "E6"
						(effects
							(font
								(size 1.27 1.27)
							)
						)
					)
				)
				(pin power_in line
					(at 0 -127 0)
					(length 3.81) hide
					(name "GND"
						(effects
							(font
								(size 1.27 1.27)
							)
						)
					)
					(number "E7"
						(effects
							(font
								(size 1.27 1.27)
							)
						)
					)
				)
				(pin power_in line
					(at 0 -127 0)
					(length 3.81) hide
					(name "GND"
						(effects
							(font
								(size 1.27 1.27)
							)
						)
					)
					(number "E8"
						(effects
							(font
								(size 1.27 1.27)
							)
						)
					)
				)
				(pin bidirectional line
					(at 58.42 -91.44 180)
					(length 3.81)
					(name "I2C_ADDR"
						(effects
							(font
								(size 1.27 1.27)
							)
						)
					)
					(number "F1"
						(effects
							(font
								(size 1.27 1.27)
							)
						)
					)
				)
				(pin bidirectional line
					(at 58.42 -111.76 180)
					(length 3.81)
					(name "BUSPOWERZ(GPIO10)"
						(effects
							(font
								(size 1.27 1.27)
							)
						)
					)
					(number "F10"
						(effects
							(font
								(size 1.27 1.27)
							)
						)
					)
				)
				(pin bidirectional line
					(at 58.42 -96.52 180)
					(length 3.81)
					(name "RESETZ(GPIO9)"
						(effects
							(font
								(size 1.27 1.27)
							)
						)
					)
					(number "F11"
						(effects
							(font
								(size 1.27 1.27)
							)
						)
					)
				)
				(pin input line
					(at 0 -96.52 0)
					(length 3.81)
					(name "UART_RX"
						(effects
							(font
								(size 1.27 1.27)
							)
						)
					)
					(number "F2"
						(effects
							(font
								(size 1.27 1.27)
							)
						)
					)
				)
				(pin bidirectional line
					(at 0 -88.9 0)
					(length 3.81)
					(name "SWD_DATA"
						(effects
							(font
								(size 1.27 1.27)
							)
						)
					)
					(number "F4"
						(effects
							(font
								(size 1.27 1.27)
							)
						)
					)
				)
				(pin power_in line
					(at 0 -127 0)
					(length 3.81) hide
					(name "GND"
						(effects
							(font
								(size 1.27 1.27)
							)
						)
					)
					(number "F5"
						(effects
							(font
								(size 1.27 1.27)
							)
						)
					)
				)
				(pin power_in line
					(at 0 -127 0)
					(length 3.81) hide
					(name "GND"
						(effects
							(font
								(size 1.27 1.27)
							)
						)
					)
					(number "F6"
						(effects
							(font
								(size 1.27 1.27)
							)
						)
					)
				)
				(pin power_in line
					(at 0 -127 0)
					(length 3.81) hide
					(name "GND"
						(effects
							(font
								(size 1.27 1.27)
							)
						)
					)
					(number "F7"
						(effects
							(font
								(size 1.27 1.27)
							)
						)
					)
				)
				(pin power_in line
					(at 0 -127 0)
					(length 3.81) hide
					(name "GND"
						(effects
							(font
								(size 1.27 1.27)
							)
						)
					)
					(number "F8"
						(effects
							(font
								(size 1.27 1.27)
							)
						)
					)
				)
				(pin power_out line
					(at 58.42 -12.7 180)
					(length 3.81)
					(name "LDO_3V3"
						(effects
							(font
								(size 1.27 1.27)
							)
						)
					)
					(number "G1"
						(effects
							(font
								(size 1.27 1.27)
							)
						)
					)
				)
				(pin bidirectional line
					(at 0 -66.04 0)
					(length 3.81)
					(name "GPIO6"
						(effects
							(font
								(size 1.27 1.27)
							)
						)
					)
					(number "G10"
						(effects
							(font
								(size 1.27 1.27)
							)
						)
					)
				)
				(pin bidirectional line
					(at 0 -58.42 0)
					(length 3.81)
					(name "GPIO3(HD3_EN)"
						(effects
							(font
								(size 1.27 1.27)
							)
						)
					)
					(number "G11"
						(effects
							(font
								(size 1.27 1.27)
							)
						)
					)
				)
				(pin bidirectional line
					(at 58.42 -116.84 180)
					(length 3.81)
					(name "R_OSC"
						(effects
							(font
								(size 1.27 1.27)
							)
						)
					)
					(number "G2"
						(effects
							(font
								(size 1.27 1.27)
							)
						)
					)
				)
				(pin input line
					(at 0 -91.44 0)
					(length 3.81)
					(name "SWD_CLK"
						(effects
							(font
								(size 1.27 1.27)
							)
						)
					)
					(number "G4"
						(effects
							(font
								(size 1.27 1.27)
							)
						)
					)
				)
				(pin power_in line
					(at 0 -127 0)
					(length 3.81) hide
					(name "GND"
						(effects
							(font
								(size 1.27 1.27)
							)
						)
					)
					(number "G5"
						(effects
							(font
								(size 1.27 1.27)
							)
						)
					)
				)
				(pin power_in line
					(at 0 -127 0)
					(length 3.81) hide
					(name "GND"
						(effects
							(font
								(size 1.27 1.27)
							)
						)
					)
					(number "G6"
						(effects
							(font
								(size 1.27 1.27)
							)
						)
					)
				)
				(pin power_in line
					(at 0 -127 0)
					(length 3.81) hide
					(name "GND"
						(effects
							(font
								(size 1.27 1.27)
							)
						)
					)
					(number "G7"
						(effects
							(font
								(size 1.27 1.27)
							)
						)
					)
				)
				(pin power_in line
					(at 0 -127 0)
					(length 3.81) hide
					(name "GND"
						(effects
							(font
								(size 1.27 1.27)
							)
						)
					)
					(number "G8"
						(effects
							(font
								(size 1.27 1.27)
							)
						)
					)
				)
				(pin power_in line
					(at 0 -25.4 0)
					(length 3.81)
					(name "VIN_3V3"
						(effects
							(font
								(size 1.27 1.27)
							)
						)
					)
					(number "H1"
						(effects
							(font
								(size 1.27 1.27)
							)
						)
					)
				)
				(pin power_in line
					(at 0 -15.24 0)
					(length 3.81)
					(name "PP_CABLE"
						(effects
							(font
								(size 1.27 1.27)
							)
						)
					)
					(number "H10"
						(effects
							(font
								(size 1.27 1.27)
							)
						)
					)
				)
				(pin power_in line
					(at 58.42 -5.08 180)
					(length 3.81)
					(name "VBUS"
						(effects
							(font
								(size 1.27 1.27)
							)
						)
					)
					(number "H11"
						(effects
							(font
								(size 1.27 1.27)
							)
						)
					)
				)
				(pin power_out line
					(at 58.42 -7.62 180)
					(length 3.81)
					(name "VOUT_3V3"
						(effects
							(font
								(size 1.27 1.27)
							)
						)
					)
					(number "H2"
						(effects
							(font
								(size 1.27 1.27)
							)
						)
					)
				)
				(pin power_in line
					(at 0 -127 0)
					(length 3.81) hide
					(name "GND"
						(effects
							(font
								(size 1.27 1.27)
							)
						)
					)
					(number "H4"
						(effects
							(font
								(size 1.27 1.27)
							)
						)
					)
				)
				(pin power_in line
					(at 0 -127 0)
					(length 3.81) hide
					(name "GND"
						(effects
							(font
								(size 1.27 1.27)
							)
						)
					)
					(number "H5"
						(effects
							(font
								(size 1.27 1.27)
							)
						)
					)
				)
				(pin bidirectional line
					(at 0 -71.12 0)
					(length 3.81)
					(name "GPIO8"
						(effects
							(font
								(size 1.27 1.27)
							)
						)
					)
					(number "H6"
						(effects
							(font
								(size 1.27 1.27)
							)
						)
					)
				)
				(pin output line
					(at 58.42 -121.92 180)
					(length 3.81)
					(name "SS"
						(effects
							(font
								(size 1.27 1.27)
							)
						)
					)
					(number "H7"
						(effects
							(font
								(size 1.27 1.27)
							)
						)
					)
				)
				(pin power_in line
					(at 0 -127 0)
					(length 3.81) hide
					(name "GND"
						(effects
							(font
								(size 1.27 1.27)
							)
						)
					)
					(number "H8"
						(effects
							(font
								(size 1.27 1.27)
							)
						)
					)
				)
				(pin bidirectional line
					(at 0 -111.76 0)
					(length 3.81)
					(name "AUX_P"
						(effects
							(font
								(size 1.27 1.27)
							)
						)
					)
					(number "J1"
						(effects
							(font
								(size 1.27 1.27)
							)
						)
					)
				)
				(pin power_in line
					(at 58.42 -5.08 180)
					(length 3.81) hide
					(name "VBUS"
						(effects
							(font
								(size 1.27 1.27)
							)
						)
					)
					(number "J10"
						(effects
							(font
								(size 1.27 1.27)
							)
						)
					)
				)
				(pin power_in line
					(at 58.42 -5.08 180)
					(length 3.81) hide
					(name "VBUS"
						(effects
							(font
								(size 1.27 1.27)
							)
						)
					)
					(number "J11"
						(effects
							(font
								(size 1.27 1.27)
							)
						)
					)
				)
				(pin bidirectional line
					(at 0 -114.3 0)
					(length 3.81)
					(name "AUX_N"
						(effects
							(font
								(size 1.27 1.27)
							)
						)
					)
					(number "J2"
						(effects
							(font
								(size 1.27 1.27)
							)
						)
					)
				)
				(pin power_out line
					(at 58.42 -17.78 180)
					(length 3.81)
					(name "LDO_1V8A"
						(effects
							(font
								(size 1.27 1.27)
							)
						)
					)
					(number "K1"
						(effects
							(font
								(size 1.27 1.27)
							)
						)
					)
				)
				(pin bidirectional line
					(at 58.42 -43.18 180)
					(length 3.81)
					(name "RPD_G2"
						(effects
							(font
								(size 1.27 1.27)
							)
						)
					)
					(number "K10"
						(effects
							(font
								(size 1.27 1.27)
							)
						)
					)
				)
				(pin power_in line
					(at 58.42 -5.08 180)
					(length 3.81) hide
					(name "VBUS"
						(effects
							(font
								(size 1.27 1.27)
							)
						)
					)
					(number "K11"
						(effects
							(font
								(size 1.27 1.27)
							)
						)
					)
				)
				(pin bidirectional line
					(at 58.42 -76.2 180)
					(length 3.81)
					(name "DEBUG2(GPIO14,HD3POL)"
						(effects
							(font
								(size 1.27 1.27)
							)
						)
					)
					(number "K2"
						(effects
							(font
								(size 1.27 1.27)
							)
						)
					)
				)
				(pin bidirectional line
					(at 58.42 -71.12 180)
					(length 3.81)
					(name "DEBUG4(GPIO12,CONFIG2)"
						(effects
							(font
								(size 1.27 1.27)
							)
						)
					)
					(number "K3"
						(effects
							(font
								(size 1.27 1.27)
							)
						)
					)
				)
				(pin output line
					(at 0 -106.68 0)
					(length 3.81)
					(name "LSX_P2R"
						(effects
							(font
								(size 1.27 1.27)
							)
						)
					)
					(number "K4"
						(effects
							(font
								(size 1.27 1.27)
							)
						)
					)
				)
				(pin bidirectional line
					(at 0 -121.92 0)
					(length 3.81)
					(name "USB_RP_N"
						(effects
							(font
								(size 1.27 1.27)
							)
						)
					)
					(number "K5"
						(effects
							(font
								(size 1.27 1.27)
							)
						)
					)
				)
				(pin bidirectional line
					(at 58.42 -48.26 180)
					(length 3.81)
					(name "C_USB_TP"
						(effects
							(font
								(size 1.27 1.27)
							)
						)
					)
					(number "K6"
						(effects
							(font
								(size 1.27 1.27)
							)
						)
					)
				)
				(pin bidirectional line
					(at 58.42 -55.88 180)
					(length 3.81)
					(name "C_USB_BP"
						(effects
							(font
								(size 1.27 1.27)
							)
						)
					)
					(number "K7"
						(effects
							(font
								(size 1.27 1.27)
							)
						)
					)
				)
				(pin bidirectional line
					(at 58.42 -63.5 180)
					(length 3.81)
					(name "C_SBU1"
						(effects
							(font
								(size 1.27 1.27)
							)
						)
					)
					(number "K8"
						(effects
							(font
								(size 1.27 1.27)
							)
						)
					)
				)
				(pin bidirectional line
					(at 58.42 -40.64 180)
					(length 3.81)
					(name "RPD_G1"
						(effects
							(font
								(size 1.27 1.27)
							)
						)
					)
					(number "K9"
						(effects
							(font
								(size 1.27 1.27)
							)
						)
					)
				)
				(pin power_in line
					(at 0 -127 0)
					(length 3.81) hide
					(name "GND"
						(effects
							(font
								(size 1.27 1.27)
							)
						)
					)
					(number "L1"
						(effects
							(font
								(size 1.27 1.27)
							)
						)
					)
				)
				(pin bidirectional line
					(at 58.42 -35.56 180)
					(length 3.81)
					(name "C_CC2"
						(effects
							(font
								(size 1.27 1.27)
							)
						)
					)
					(number "L10"
						(effects
							(font
								(size 1.27 1.27)
							)
						)
					)
				)
				(pin no_connect line
					(at 3.81 -123.19 0)
					(length 3.81) hide
					(name "NC"
						(effects
							(font
								(size 1.27 1.27)
							)
						)
					)
					(number "L11"
						(effects
							(font
								(size 1.27 1.27)
							)
						)
					)
				)
				(pin bidirectional line
					(at 58.42 -78.74 180)
					(length 3.81)
					(name "DEBUG1(GPIO15)"
						(effects
							(font
								(size 1.27 1.27)
							)
						)
					)
					(number "L2"
						(effects
							(font
								(size 1.27 1.27)
							)
						)
					)
				)
				(pin bidirectional line
					(at 58.42 -73.66 180)
					(length 3.81)
					(name "DEBUG3(GPIO13,CONFIG1)"
						(effects
							(font
								(size 1.27 1.27)
							)
						)
					)
					(number "L3"
						(effects
							(font
								(size 1.27 1.27)
							)
						)
					)
				)
				(pin input line
					(at 0 -104.14 0)
					(length 3.81)
					(name "LSX_R2P"
						(effects
							(font
								(size 1.27 1.27)
							)
						)
					)
					(number "L4"
						(effects
							(font
								(size 1.27 1.27)
							)
						)
					)
				)
				(pin bidirectional line
					(at 0 -119.38 0)
					(length 3.81)
					(name "USB_RP_P"
						(effects
							(font
								(size 1.27 1.27)
							)
						)
					)
					(number "L5"
						(effects
							(font
								(size 1.27 1.27)
							)
						)
					)
				)
				(pin bidirectional line
					(at 58.42 -50.8 180)
					(length 3.81)
					(name "C_USB_TN"
						(effects
							(font
								(size 1.27 1.27)
							)
						)
					)
					(number "L6"
						(effects
							(font
								(size 1.27 1.27)
							)
						)
					)
				)
				(pin bidirectional line
					(at 58.42 -58.42 180)
					(length 3.81)
					(name "C_USB_BN"
						(effects
							(font
								(size 1.27 1.27)
							)
						)
					)
					(number "L7"
						(effects
							(font
								(size 1.27 1.27)
							)
						)
					)
				)
				(pin bidirectional line
					(at 58.42 -66.04 180)
					(length 3.81)
					(name "C_SBU2"
						(effects
							(font
								(size 1.27 1.27)
							)
						)
					)
					(number "L8"
						(effects
							(font
								(size 1.27 1.27)
							)
						)
					)
				)
				(pin bidirectional line
					(at 58.42 -33.02 180)
					(length 3.81)
					(name "C_CC1"
						(effects
							(font
								(size 1.27 1.27)
							)
						)
					)
					(number "L9"
						(effects
							(font
								(size 1.27 1.27)
							)
						)
					)
				)
			)
		)
	(symbol "antmicroLEDIndicationDiscrete:LED_G_0603_KP-1608CGCK"
			(pin_numbers hide)
			(pin_names hide)
			(exclude_from_sim no)
			(in_bom yes)
			(on_board yes)
			(property "Reference" "D"
				(at 22.86 -2.54 0)
				(effects
					(font
						(size 1.27 1.27)
						(thickness 0.15)
					)
					(justify left bottom)
				)
			)
			(property "Value" "LED_G_0603_KP-1608CGCK"
				(at 22.86 -7.62 0)
				(effects
					(font
						(size 1.27 1.27)
						(thickness 0.15)
					)
					(justify left bottom)
					(hide yes)
				)
			)
			(property "Footprint" "antmicro-footprints:LED_0603_1608Metric_G"
				(at 22.86 -10.16 0)
				(effects
					(font
						(size 1.27 1.27)
						(thickness 0.15)
					)
					(justify left bottom)
					(hide yes)
				)
			)
			(property "Datasheet" "http://www.kingbright.com/attachments/file/psearch//000/00/00/KP-1608CGCK(Ver.23B).pdf"
				(at 22.86 -12.7 0)
				(effects
					(font
						(size 1.27 1.27)
						(thickness 0.15)
					)
					(justify left bottom)
					(hide yes)
				)
			)
			(property "Description" "LED, Green, SMD, 0603, 20 mA, 2.1 V, 570 nm"
				(at 0 0 0)
				(effects
					(font
						(size 1.27 1.27)
					)
					(hide yes)
				)
			)
			(property "MPN" "KP-1608CGCK"
				(at 22.86 -15.24 0)
				(effects
					(font
						(size 1.27 1.27)
						(thickness 0.15)
					)
					(justify left bottom)
					(hide yes)
				)
			)
			(property "Manufacturer" "Kingbright"
				(at 22.86 -17.78 0)
				(effects
					(font
						(size 1.27 1.27)
						(thickness 0.15)
					)
					(justify left bottom)
					(hide yes)
				)
			)
			(property "Color" "Green"
				(at 22.86 -5.08 0)
				(effects
					(font
						(size 1.27 1.27)
					)
					(justify left bottom)
				)
			)
			(property "Author" "Antmicro"
				(at 22.86 -20.32 0)
				(effects
					(font
						(size 1.27 1.27)
						(thickness 0.15)
					)
					(justify left bottom)
					(hide yes)
				)
			)
			(property "License" "Apache-2.0"
				(at 22.86 -22.86 0)
				(effects
					(font
						(size 1.27 1.27)
						(thickness 0.15)
					)
					(justify left bottom)
					(hide yes)
				)
			)
			(property "ki_keywords" "SMT, DIODE, SEMICONDUCTOR, LED"
				(at 0 0 0)
				(effects
					(font
						(size 1.27 1.27)
					)
					(hide yes)
				)
			)
			(symbol "LED_G_0603_KP-1608CGCK_0_1"
				(polyline
					(pts
						(xy 1.905 0) (xy 0.635 0)
					)
					(stroke
						(width 0)
						(type default)
					)
					(fill
						(type none)
					)
				)
				(polyline
					(pts
						(xy 4.445 0) (xy 3.175 0)
					)
					(stroke
						(width 0)
						(type default)
					)
					(fill
						(type none)
					)
				)
			)
			(symbol "LED_G_0603_KP-1608CGCK_1_1"
				(polyline
					(pts
						(xy 1.778 1.016) (xy 1.778 -1.016)
					)
					(stroke
						(width 0.254)
						(type default)
					)
					(fill
						(type none)
					)
				)
				(polyline
					(pts
						(xy 3.302 1.016) (xy 3.302 -1.016) (xy 1.778 0) (xy 3.302 1.016)
					)
					(stroke
						(width 0.254)
						(type default)
					)
					(fill
						(type outline)
					)
				)
				(polyline
					(pts
						(xy 1.143 2.286) (xy 1.143 1.778) (xy 1.143 2.286) (xy 1.651 2.286) (xy 1.143 2.286) (xy 2.159 1.27)
					)
					(stroke
						(width 0.254)
						(type default)
					)
					(fill
						(type none)
					)
				)
				(polyline
					(pts
						(xy 2.159 2.54) (xy 2.159 2.032) (xy 2.159 2.54) (xy 2.667 2.54) (xy 2.159 2.54) (xy 3.048 1.651)
					)
					(stroke
						(width 0.254)
						(type default)
					)
					(fill
						(type none)
					)
				)
				(pin passive line
					(at 0 0 0)
					(length 0.635)
					(name "C"
						(effects
							(font
								(size 1.27 1.27)
							)
						)
					)
					(number "1"
						(effects
							(font
								(size 1.27 1.27)
							)
						)
					)
				)
				(pin passive line
					(at 5.08 0 180)
					(length 0.635)
					(name "A"
						(effects
							(font
								(size 1.27 1.27)
							)
						)
					)
					(number "2"
						(effects
							(font
								(size 1.27 1.27)
							)
						)
					)
				)
			)
		)
	(symbol "antmicroLEDIndicationDiscrete:LED_RGB_0606_150066M153000"
			(exclude_from_sim no)
			(in_bom yes)
			(on_board yes)
			(property "Reference" "D"
				(at 27.94 -2.54 0)
				(effects
					(font
						(size 1.27 1.27)
						(thickness 0.15)
					)
					(justify left bottom)
				)
			)
			(property "Value" "LED_RGB_0606_150066M153000"
				(at 27.94 -7.62 0)
				(effects
					(font
						(size 1.27 1.27)
						(thickness 0.15)
					)
					(justify left bottom)
					(hide yes)
				)
			)
			(property "Footprint" "antmicro-footprints:LED_Dual0603"
				(at 27.94 -10.16 0)
				(effects
					(font
						(size 1.27 1.27)
						(thickness 0.15)
					)
					(justify left bottom)
					(hide yes)
				)
			)
			(property "Datasheet" "https://www.we-online.com/components/products/datasheet/150066M153000.pdf"
				(at 27.94 -12.7 0)
				(effects
					(font
						(size 1.27 1.27)
						(thickness 0.15)
					)
					(justify left bottom)
					(hide yes)
				)
			)
			(property "Description" "LED, RGB, SMD, 0606, R 20 mA, G 20 mA, B 20 mA, R 2 V, G 3.3 V, B 3.3 V, Common Anode"
				(at 0 0 0)
				(effects
					(font
						(size 1.27 1.27)
					)
					(hide yes)
				)
			)
			(property "MPN" "150066M153000"
				(at 27.94 -15.24 0)
				(effects
					(font
						(size 1.27 1.27)
						(thickness 0.15)
					)
					(justify left bottom)
					(hide yes)
				)
			)
			(property "Manufacturer" "Würth Elektronik"
				(at 27.94 -17.78 0)
				(effects
					(font
						(size 1.27 1.27)
						(thickness 0.15)
					)
					(justify left bottom)
					(hide yes)
				)
			)
			(property "Color" "R, G, B"
				(at 27.94 -5.08 0)
				(effects
					(font
						(size 1.27 1.27)
					)
					(justify left bottom)
				)
			)
			(property "Author" "Antmicro"
				(at 27.94 -20.32 0)
				(effects
					(font
						(size 1.27 1.27)
						(thickness 0.15)
					)
					(justify left bottom)
					(hide yes)
				)
			)
			(property "License" "Apache-2.0"
				(at 27.94 -22.86 0)
				(effects
					(font
						(size 1.27 1.27)
						(thickness 0.15)
					)
					(justify left bottom)
					(hide yes)
				)
			)
			(property "ki_keywords" "SMT, DIODE, SEMICONDUCTOR, LED"
				(at 0 0 0)
				(effects
					(font
						(size 1.27 1.27)
					)
					(hide yes)
				)
			)
			(symbol "LED_RGB_0606_150066M153000_1_1"
				(polyline
					(pts
						(xy 6.35 -7.62) (xy 8.89 -7.62)
					)
					(stroke
						(width 0.254)
						(type default)
					)
					(fill
						(type none)
					)
				)
				(polyline
					(pts
						(xy 6.35 -3.81) (xy 8.89 -3.81)
					)
					(stroke
						(width 0.254)
						(type default)
					)
					(fill
						(type none)
					)
				)
				(polyline
					(pts
						(xy 6.35 0) (xy 8.89 0)
					)
					(stroke
						(width 0.254)
						(type default)
					)
					(fill
						(type none)
					)
				)
				(polyline
					(pts
						(xy 8.763 -6.604) (xy 8.763 -8.636)
					)
					(stroke
						(width 0.254)
						(type default)
					)
					(fill
						(type none)
					)
				)
				(polyline
					(pts
						(xy 8.763 -2.794) (xy 8.763 -4.826)
					)
					(stroke
						(width 0.254)
						(type default)
					)
					(fill
						(type none)
					)
				)
				(polyline
					(pts
						(xy 8.763 1.016) (xy 8.763 -1.016)
					)
					(stroke
						(width 0.254)
						(type default)
					)
					(fill
						(type none)
					)
				)
				(polyline
					(pts
						(xy 12.7 -3.81) (xy 13.97 -3.81)
					)
					(stroke
						(width 0.254)
						(type default)
					)
					(fill
						(type none)
					)
				)
				(polyline
					(pts
						(xy 12.7 -3.81) (xy 12.7 -7.62) (xy 10.16 -7.62)
					)
					(stroke
						(width 0.254)
						(type default)
					)
					(fill
						(type none)
					)
				)
				(polyline
					(pts
						(xy 10.16 -3.81) (xy 12.7 -3.81) (xy 12.7 0) (xy 10.16 0)
					)
					(stroke
						(width 0.254)
						(type default)
					)
					(fill
						(type none)
					)
				)
				(polyline
					(pts
						(xy 10.287 -6.604) (xy 10.287 -8.636) (xy 8.763 -7.62) (xy 10.287 -6.604)
					)
					(stroke
						(width 0.254)
						(type default)
					)
					(fill
						(type outline)
					)
				)
				(polyline
					(pts
						(xy 10.287 -2.794) (xy 10.287 -4.826) (xy 8.763 -3.81) (xy 10.287 -2.794)
					)
					(stroke
						(width 0.254)
						(type default)
					)
					(fill
						(type outline)
					)
				)
				(polyline
					(pts
						(xy 10.287 1.016) (xy 10.287 -1.016) (xy 8.763 0) (xy 10.287 1.016)
					)
					(stroke
						(width 0.254)
						(type default)
					)
					(fill
						(type outline)
					)
				)
				(polyline
					(pts
						(xy 8.128 -5.334) (xy 8.128 -5.842) (xy 8.128 -5.334) (xy 8.636 -5.334) (xy 8.128 -5.334) (xy 9.144 -6.35)
					)
					(stroke
						(width 0.254)
						(type default)
					)
					(fill
						(type none)
					)
				)
				(polyline
					(pts
						(xy 8.128 -1.524) (xy 8.128 -2.032) (xy 8.128 -1.524) (xy 8.636 -1.524) (xy 8.128 -1.524) (xy 9.144 -2.54)
					)
					(stroke
						(width 0.254)
						(type default)
					)
					(fill
						(type none)
					)
				)
				(polyline
					(pts
						(xy 8.128 2.286) (xy 8.128 1.778) (xy 8.128 2.286) (xy 8.636 2.286) (xy 8.128 2.286) (xy 9.144 1.27)
					)
					(stroke
						(width 0.254)
						(type default)
					)
					(fill
						(type none)
					)
				)
				(polyline
					(pts
						(xy 9.144 -5.08) (xy 9.144 -5.588) (xy 9.144 -5.08) (xy 9.652 -5.08) (xy 9.144 -5.08) (xy 10.033 -5.969)
					)
					(stroke
						(width 0.254)
						(type default)
					)
					(fill
						(type none)
					)
				)
				(polyline
					(pts
						(xy 9.144 -1.27) (xy 9.144 -1.778) (xy 9.144 -1.27) (xy 9.652 -1.27) (xy 9.144 -1.27) (xy 10.033 -2.159)
					)
					(stroke
						(width 0.254)
						(type default)
					)
					(fill
						(type none)
					)
				)
				(polyline
					(pts
						(xy 9.144 2.54) (xy 9.144 2.032) (xy 9.144 2.54) (xy 9.652 2.54) (xy 9.144 2.54) (xy 10.033 1.651)
					)
					(stroke
						(width 0.254)
						(type default)
					)
					(fill
						(type none)
					)
				)
				(rectangle
					(start 2.54 -11.43)
					(end 16.51 3.81)
					(stroke
						(width 0.254)
						(type default)
					)
					(fill
						(type background)
					)
				)
				(pin passive line
					(at 0 0 0)
					(length 2.54)
					(name "C_{R}"
						(effects
							(font
								(size 1.27 1.27)
							)
						)
					)
					(number "1"
						(effects
							(font
								(size 1.27 1.27)
							)
						)
					)
				)
				(pin passive line
					(at 0 -3.81 0)
					(length 2.54)
					(name "C_{G}"
						(effects
							(font
								(size 1.27 1.27)
							)
						)
					)
					(number "2"
						(effects
							(font
								(size 1.27 1.27)
							)
						)
					)
				)
				(pin passive line
					(at 0 -7.62 0)
					(length 2.54)
					(name "C_{B}"
						(effects
							(font
								(size 1.27 1.27)
							)
						)
					)
					(number "3"
						(effects
							(font
								(size 1.27 1.27)
							)
						)
					)
				)
				(pin passive line
					(at 19.05 -3.81 180)
					(length 2.54)
					(name "A"
						(effects
							(font
								(size 1.27 1.27)
							)
						)
					)
					(number "4"
						(effects
							(font
								(size 1.27 1.27)
							)
						)
					)
				)
			)
		)
	(symbol "antmicroMechanicalParts:Lightpipe_Mentor_1271.1001"
			(pin_names hide)
			(exclude_from_sim no)
			(in_bom yes)
			(on_board yes)
			(property "Reference" "H"
				(at 20.32 -2.54 0)
				(effects
					(font
						(size 1.27 1.27)
						(thickness 0.15)
					)
					(justify left bottom)
				)
			)
			(property "Value" "Lightpipe_Mentor_1271.1001"
				(at 20.32 -7.62 0)
				(effects
					(font
						(size 1.27 1.27)
						(thickness 0.15)
					)
					(justify left bottom)
					(hide yes)
				)
			)
			(property "Footprint" "antmicro-footprints:Mech_Lightpipe_Mentor_1271.1001"
				(at 20.32 -10.16 0)
				(effects
					(font
						(size 1.27 1.27)
						(thickness 0.15)
					)
					(justify left bottom)
					(hide yes)
				)
			)
			(property "Datasheet" "https://www.mentor.de.com/productpdfs/ll/ll14-20.pdf"
				(at 20.32 -12.7 0)
				(effects
					(font
						(size 1.27 1.27)
						(thickness 0.15)
					)
					(justify left bottom)
					(hide yes)
				)
			)
			(property "Description" "Light Pipe, 14.45 mm, 1 Pipe, Circular, PC Board, Transparent"
				(at 0 0 0)
				(effects
					(font
						(size 1.27 1.27)
					)
					(hide yes)
				)
			)
			(property "MPN" "1271.1001"
				(at 20.32 -5.08 0)
				(effects
					(font
						(size 1.27 1.27)
						(thickness 0.15)
					)
					(justify left bottom)
				)
			)
			(property "Manufacturer" "Mentor Worldwide"
				(at 20.32 -15.24 0)
				(effects
					(font
						(size 1.27 1.27)
						(thickness 0.15)
					)
					(justify left bottom)
					(hide yes)
				)
			)
			(property "Author" "Antmicro"
				(at 20.32 -17.78 0)
				(effects
					(font
						(size 1.27 1.27)
						(thickness 0.15)
					)
					(justify left bottom)
					(hide yes)
				)
			)
			(property "License" "Apache-2.0"
				(at 20.32 -20.32 0)
				(effects
					(font
						(size 1.27 1.27)
						(thickness 0.15)
					)
					(justify left bottom)
					(hide yes)
				)
			)
			(property "ki_keywords" "HORIZONTAL, THT, MECHANICAL"
				(at 0 0 0)
				(effects
					(font
						(size 1.27 1.27)
					)
					(hide yes)
				)
			)
			(symbol "Lightpipe_Mentor_1271.1001_1_1"
				(rectangle
					(start 5.08 -2.54)
					(end -5.08 3.81)
					(stroke
						(width 0.254)
						(type default)
					)
					(fill
						(type background)
					)
				)
				(text "1x1"
					(at -1.905 -2.54 0)
					(effects
						(font
							(size 1.27 1.27)
							(thickness 0.15)
						)
						(justify left bottom)
					)
				)
				(text "Horizontal"
					(at -5.08 1.524 0)
					(effects
						(font
							(size 1.27 1.27)
							(thickness 0.15)
						)
						(justify left bottom)
					)
				)
				(text "lightguide"
					(at -4.826 -0.508 0)
					(effects
						(font
							(size 1.27 1.27)
							(thickness 0.15)
						)
						(justify left bottom)
					)
				)
			)
		)
	(symbol "antmicroMechanicalParts:MP_Pad3.5mm_Drill2.2mm"
			(pin_names hide)
			(exclude_from_sim no)
			(in_bom no)
			(on_board yes)
			(property "Reference" "MP"
				(at 15.24 -5.08 0)
				(effects
					(font
						(size 1.27 1.27)
						(thickness 0.15)
					)
					(justify left bottom)
				)
			)
			(property "Value" "MP_Pad3.5mm_Drill2.2mm"
				(at 15.24 -7.62 0)
				(effects
					(font
						(size 1.27 1.27)
						(thickness 0.15)
					)
					(justify left bottom)
				)
			)
			(property "Footprint" "antmicro-footprints:MP_Pad3.5mm_Drill2.2mm"
				(at 15.24 -10.16 0)
				(effects
					(font
						(size 1.27 1.27)
						(thickness 0.15)
					)
					(justify left bottom)
					(hide yes)
				)
			)
			(property "Datasheet" ""
				(at 16.84 -15.57 0)
				(effects
					(font
						(size 1.27 1.27)
						(thickness 0.15)
					)
					(justify left bottom)
					(hide yes)
				)
			)
			(property "Description" "PCB mounting point"
				(at 0 0 0)
				(effects
					(font
						(size 1.27 1.27)
					)
					(hide yes)
				)
			)
			(property "Author" "Antmicro"
				(at 15.24 -15.24 0)
				(effects
					(font
						(size 1.27 1.27)
						(thickness 0.15)
					)
					(justify left bottom)
					(hide yes)
				)
			)
			(property "License" "Apache-2.0"
				(at 15.24 -17.78 0)
				(effects
					(font
						(size 1.27 1.27)
						(thickness 0.15)
					)
					(justify left bottom)
					(hide yes)
				)
			)
			(property "ki_keywords" "MECHANICAL"
				(at 0 0 0)
				(effects
					(font
						(size 1.27 1.27)
					)
					(hide yes)
				)
			)
			(symbol "MP_Pad3.5mm_Drill2.2mm_1_1"
				(circle
					(center 5.08 0)
					(radius 1.27)
					(stroke
						(width 0.254)
						(type default)
					)
					(fill
						(type background)
					)
				)
				(circle
					(center 5.08 0)
					(radius 2.54)
					(stroke
						(width 0.254)
						(type default)
					)
					(fill
						(type background)
					)
				)
				(pin passive line
					(at 0 0 0)
					(length 2.54)
					(name "~"
						(effects
							(font
								(size 1.27 1.27)
							)
						)
					)
					(number "1"
						(effects
							(font
								(size 1.27 1.27)
							)
						)
					)
				)
			)
		)
	(symbol "antmicroMechanicalParts:MP_Pad6mm_Drill3mm"
			(pin_names hide)
			(exclude_from_sim no)
			(in_bom no)
			(on_board yes)
			(property "Reference" "MP"
				(at 20.32 -2.54 0)
				(effects
					(font
						(size 1.27 1.27)
						(thickness 0.15)
					)
					(justify left bottom)
				)
			)
			(property "Value" "MP_Pad6mm_Drill3mm"
				(at 20.32 -5.08 0)
				(effects
					(font
						(size 1.27 1.27)
						(thickness 0.15)
					)
					(justify left bottom)
				)
			)
			(property "Footprint" "antmicro-footprints:MP_Pad6mm_Drill3mm"
				(at 20.32 -7.62 0)
				(effects
					(font
						(size 1.27 1.27)
						(thickness 0.15)
					)
					(justify left bottom)
					(hide yes)
				)
			)
			(property "Datasheet" ""
				(at 16.84 -15.57 0)
				(effects
					(font
						(size 1.27 1.27)
						(thickness 0.15)
					)
					(justify left bottom)
					(hide yes)
				)
			)
			(property "Description" "Mechanical part"
				(at 0 0 0)
				(effects
					(font
						(size 1.27 1.27)
					)
					(hide yes)
				)
			)
			(property "Author" "Antmicro"
				(at 20.32 -10.16 0)
				(effects
					(font
						(size 1.27 1.27)
						(thickness 0.15)
					)
					(justify left bottom)
					(hide yes)
				)
			)
			(property "License" "Apache-2.0"
				(at 20.32 -12.7 0)
				(effects
					(font
						(size 1.27 1.27)
						(thickness 0.15)
					)
					(justify left bottom)
					(hide yes)
				)
			)
			(property "ki_keywords" "MECHANICAL"
				(at 0 0 0)
				(effects
					(font
						(size 1.27 1.27)
					)
					(hide yes)
				)
			)
			(symbol "MP_Pad6mm_Drill3mm_1_1"
				(circle
					(center 5.08 0)
					(radius 1.27)
					(stroke
						(width 0.254)
						(type default)
					)
					(fill
						(type background)
					)
				)
				(circle
					(center 5.08 0)
					(radius 2.54)
					(stroke
						(width 0.254)
						(type default)
					)
					(fill
						(type background)
					)
				)
				(pin passive line
					(at 0 0 0)
					(length 2.54)
					(name "~"
						(effects
							(font
								(size 1.27 1.27)
							)
						)
					)
					(number "1"
						(effects
							(font
								(size 1.27 1.27)
							)
						)
					)
				)
			)
		)
	(symbol "antmicroMechanicalParts:antmicro_logo"
			(exclude_from_sim no)
			(in_bom no)
			(on_board yes)
			(property "Reference" "N"
				(at 15.24 -5.08 0)
				(effects
					(font
						(size 1.27 1.27)
						(thickness 0.15)
					)
					(justify left bottom)
				)
			)
			(property "Value" "antmicro_logo"
				(at 15.24 -7.62 0)
				(effects
					(font
						(size 1.27 1.27)
						(thickness 0.15)
					)
					(justify left bottom)
				)
			)
			(property "Footprint" "antmicro-footprints:antmicro-logo"
				(at 15.24 -10.16 0)
				(effects
					(font
						(size 1.27 1.27)
						(thickness 0.15)
					)
					(justify left bottom)
					(hide yes)
				)
			)
			(property "Datasheet" ""
				(at 15.24 -12.7 0)
				(effects
					(font
						(size 1.27 1.27)
						(thickness 0.15)
					)
					(justify left bottom)
					(hide yes)
				)
			)
			(property "Description" "Mechanical part"
				(at 0 0 0)
				(effects
					(font
						(size 1.27 1.27)
					)
					(hide yes)
				)
			)
			(property "MPN" ""
				(at 0 0 0)
				(effects
					(font
						(size 1.27 1.27)
					)
				)
			)
			(property "Manufacturer" ""
				(at 15.24 -20.32 0)
				(effects
					(font
						(size 1.27 1.27)
						(thickness 0.15)
					)
					(justify left bottom)
					(hide yes)
				)
			)
			(property "Author" "Antmicro"
				(at 15.24 -15.24 0)
				(effects
					(font
						(size 1.27 1.27)
						(thickness 0.15)
					)
					(justify left bottom)
					(hide yes)
				)
			)
			(property "License" "Apache-2.0"
				(at 15.24 -17.78 0)
				(effects
					(font
						(size 1.27 1.27)
						(thickness 0.15)
					)
					(justify left bottom)
					(hide yes)
				)
			)
			(symbol "antmicro_logo_1_1"
				(text "Logo"
					(at 0 0 0)
					(effects
						(font
							(size 1.27 1.27)
							(thickness 0.15)
						)
						(justify left bottom)
					)
				)
			)
		)
	(symbol "antmicroMemory:MX25L8006EM1I-12G"
			(exclude_from_sim no)
			(in_bom yes)
			(on_board yes)
			(property "Reference" "U"
				(at 35.56 0 0)
				(effects
					(font
						(size 1.27 1.27)
						(thickness 0.15)
					)
					(justify left bottom)
				)
			)
			(property "Value" "MX25L8006EM1I-12G"
				(at 35.56 -2.54 0)
				(effects
					(font
						(size 1.27 1.27)
						(thickness 0.15)
					)
					(justify left bottom)
					(hide yes)
				)
			)
			(property "Footprint" "antmicro-footprints:SOIC-8_3.9x4.9x1.75mm_P1.27mm"
				(at 35.56 -5.08 0)
				(effects
					(font
						(size 1.27 1.27)
						(thickness 0.15)
					)
					(justify left bottom)
					(hide yes)
				)
			)
			(property "Datasheet" "https://www.macronix.com/Lists/Datasheet/Attachments/8680/MX25L8006E,%203V,%208Mb,%20v1.6.pdf"
				(at 35.56 -7.62 0)
				(effects
					(font
						(size 1.27 1.27)
						(thickness 0.15)
					)
					(justify left bottom)
					(hide yes)
				)
			)
			(property "Description" "FLASH - NOR Memory IC 8Mbit SPI 86 MHz 8-SOP"
				(at 0 0 0)
				(effects
					(font
						(size 1.27 1.27)
					)
					(hide yes)
				)
			)
			(property "MPN" "MX25L8006EM1I-12G"
				(at 35.56 -10.16 0)
				(effects
					(font
						(size 1.27 1.27)
						(thickness 0.15)
					)
					(justify left bottom)
				)
			)
			(property "Manufacturer" "Macronix"
				(at 35.56 -12.7 0)
				(effects
					(font
						(size 1.27 1.27)
						(thickness 0.15)
					)
					(justify left bottom)
					(hide yes)
				)
			)
			(property "Author" "Antmicro"
				(at 35.56 -15.24 0)
				(effects
					(font
						(size 1.27 1.27)
						(thickness 0.15)
					)
					(justify left bottom)
					(hide yes)
				)
			)
			(property "License" "Apache-2.0"
				(at 35.56 -17.78 0)
				(effects
					(font
						(size 1.27 1.27)
						(thickness 0.15)
					)
					(justify left bottom)
					(hide yes)
				)
			)
			(property "ki_keywords" "SMT, MEMORY, IC, FLASH"
				(at 0 0 0)
				(effects
					(font
						(size 1.27 1.27)
					)
					(hide yes)
				)
			)
			(symbol "MX25L8006EM1I-12G_0_1"
				(rectangle
					(start 2.54 2.54)
					(end 22.86 -13.97)
					(stroke
						(width 0.254)
						(type default)
					)
					(fill
						(type background)
					)
				)
			)
			(symbol "MX25L8006EM1I-12G_1_1"
				(pin input line
					(at 0 -12.7 0)
					(length 2.54)
					(name "~{CS}"
						(effects
							(font
								(size 1.27 1.27)
							)
						)
					)
					(number "1"
						(effects
							(font
								(size 1.27 1.27)
							)
						)
					)
				)
				(pin input line
					(at 0 -2.54 0)
					(length 2.54)
					(name "SO/IO1"
						(effects
							(font
								(size 1.27 1.27)
							)
						)
					)
					(number "2"
						(effects
							(font
								(size 1.27 1.27)
							)
						)
					)
				)
				(pin input line
					(at 0 -5.08 0)
					(length 2.54)
					(name "~{WP}"
						(effects
							(font
								(size 1.27 1.27)
							)
						)
					)
					(number "3"
						(effects
							(font
								(size 1.27 1.27)
							)
						)
					)
				)
				(pin power_in line
					(at 25.4 -10.16 180)
					(length 2.54)
					(name "GND"
						(effects
							(font
								(size 1.27 1.27)
							)
						)
					)
					(number "4"
						(effects
							(font
								(size 1.27 1.27)
							)
						)
					)
				)
				(pin input line
					(at 0 0 0)
					(length 2.54)
					(name "SI/IO0"
						(effects
							(font
								(size 1.27 1.27)
							)
						)
					)
					(number "5"
						(effects
							(font
								(size 1.27 1.27)
							)
						)
					)
				)
				(pin input line
					(at 0 -10.16 0)
					(length 2.54)
					(name "SCLK"
						(effects
							(font
								(size 1.27 1.27)
							)
						)
					)
					(number "6"
						(effects
							(font
								(size 1.27 1.27)
							)
						)
					)
				)
				(pin input line
					(at 0 -7.62 0)
					(length 2.54)
					(name "~{HOLD}"
						(effects
							(font
								(size 1.27 1.27)
							)
						)
					)
					(number "7"
						(effects
							(font
								(size 1.27 1.27)
							)
						)
					)
				)
				(pin power_in line
					(at 25.4 -1.27 180)
					(length 2.54)
					(name "VCC"
						(effects
							(font
								(size 1.27 1.27)
							)
						)
					)
					(number "8"
						(effects
							(font
								(size 1.27 1.27)
							)
						)
					)
				)
			)
		)
	(symbol "antmicroMemory:MX25L8006EM2I-12G"
			(exclude_from_sim no)
			(in_bom yes)
			(on_board yes)
			(property "Reference" "U"
				(at 35.56 0 0)
				(effects
					(font
						(size 1.27 1.27)
						(thickness 0.15)
					)
					(justify left bottom)
				)
			)
			(property "Value" "MX25L8006EM2I-12G"
				(at 35.56 -2.54 0)
				(effects
					(font
						(size 1.27 1.27)
						(thickness 0.15)
					)
					(justify left bottom)
					(hide yes)
				)
			)
			(property "Footprint" "antmicro-footprints:SOIC-8_5.3x5.3x2mm_P1.27mm"
				(at 35.56 -5.08 0)
				(effects
					(font
						(size 1.27 1.27)
						(thickness 0.15)
					)
					(justify left bottom)
					(hide yes)
				)
			)
			(property "Datasheet" "https://www.macronix.com/Lists/Datasheet/Attachments/8680/MX25L8006E,%203V,%208Mb,%20v1.6.pdf"
				(at 35.56 -7.62 0)
				(effects
					(font
						(size 1.27 1.27)
						(thickness 0.15)
					)
					(justify left bottom)
					(hide yes)
				)
			)
			(property "Description" "FLASH - NOR Memory IC 8Mbit SPI 86 MHz 8-SOP"
				(at 0 0 0)
				(effects
					(font
						(size 1.27 1.27)
					)
					(hide yes)
				)
			)
			(property "MPN" "MX25L8006EM2I-12G"
				(at 35.56 -10.16 0)
				(effects
					(font
						(size 1.27 1.27)
						(thickness 0.15)
					)
					(justify left bottom)
				)
			)
			(property "Manufacturer" "Macronix"
				(at 35.56 -12.7 0)
				(effects
					(font
						(size 1.27 1.27)
						(thickness 0.15)
					)
					(justify left bottom)
					(hide yes)
				)
			)
			(property "Author" "Antmicro"
				(at 35.56 -15.24 0)
				(effects
					(font
						(size 1.27 1.27)
						(thickness 0.15)
					)
					(justify left bottom)
					(hide yes)
				)
			)
			(property "License" "Apache-2.0"
				(at 35.56 -17.78 0)
				(effects
					(font
						(size 1.27 1.27)
						(thickness 0.15)
					)
					(justify left bottom)
					(hide yes)
				)
			)
			(property "ki_keywords" "SMT, MEMORY, IC, FLASH, SPI"
				(at 0 0 0)
				(effects
					(font
						(size 1.27 1.27)
					)
					(hide yes)
				)
			)
			(symbol "MX25L8006EM2I-12G_0_1"
				(rectangle
					(start 2.54 2.54)
					(end 22.86 -13.97)
					(stroke
						(width 0.254)
						(type default)
					)
					(fill
						(type background)
					)
				)
			)
			(symbol "MX25L8006EM2I-12G_1_1"
				(pin input line
					(at 0 -12.7 0)
					(length 2.54)
					(name "~{CS}"
						(effects
							(font
								(size 1.27 1.27)
							)
						)
					)
					(number "1"
						(effects
							(font
								(size 1.27 1.27)
							)
						)
					)
				)
				(pin input line
					(at 0 -2.54 0)
					(length 2.54)
					(name "SO/IO1"
						(effects
							(font
								(size 1.27 1.27)
							)
						)
					)
					(number "2"
						(effects
							(font
								(size 1.27 1.27)
							)
						)
					)
				)
				(pin input line
					(at 0 -5.08 0)
					(length 2.54)
					(name "~{WP}"
						(effects
							(font
								(size 1.27 1.27)
							)
						)
					)
					(number "3"
						(effects
							(font
								(size 1.27 1.27)
							)
						)
					)
				)
				(pin power_in line
					(at 25.4 -10.16 180)
					(length 2.54)
					(name "GND"
						(effects
							(font
								(size 1.27 1.27)
							)
						)
					)
					(number "4"
						(effects
							(font
								(size 1.27 1.27)
							)
						)
					)
				)
				(pin input line
					(at 0 0 0)
					(length 2.54)
					(name "SI/IO0"
						(effects
							(font
								(size 1.27 1.27)
							)
						)
					)
					(number "5"
						(effects
							(font
								(size 1.27 1.27)
							)
						)
					)
				)
				(pin input line
					(at 0 -10.16 0)
					(length 2.54)
					(name "SCLK"
						(effects
							(font
								(size 1.27 1.27)
							)
						)
					)
					(number "6"
						(effects
							(font
								(size 1.27 1.27)
							)
						)
					)
				)
				(pin input line
					(at 0 -7.62 0)
					(length 2.54)
					(name "~{HOLD}"
						(effects
							(font
								(size 1.27 1.27)
							)
						)
					)
					(number "7"
						(effects
							(font
								(size 1.27 1.27)
							)
						)
					)
				)
				(pin power_in line
					(at 25.4 -1.27 180)
					(length 2.54)
					(name "VCC"
						(effects
							(font
								(size 1.27 1.27)
							)
						)
					)
					(number "8"
						(effects
							(font
								(size 1.27 1.27)
							)
						)
					)
				)
			)
		)
	(symbol "antmicroOperationalAmplifiers:MCP6541_SOT23-5"
			(exclude_from_sim no)
			(in_bom yes)
			(on_board yes)
			(property "Reference" "U"
				(at 25.4 -5.08 0)
				(effects
					(font
						(size 1.27 1.27)
						(thickness 0.15)
					)
					(justify left bottom)
				)
			)
			(property "Value" "MCP6541_SOT23-5"
				(at 25.4 -10.16 0)
				(effects
					(font
						(size 1.27 1.27)
						(thickness 0.15)
					)
					(justify left bottom)
					(hide yes)
				)
			)
			(property "Footprint" "antmicro-footprints:SOT-23-5"
				(at 25.4 -12.7 0)
				(effects
					(font
						(size 1.27 1.27)
						(thickness 0.15)
					)
					(justify left bottom)
					(hide yes)
				)
			)
			(property "Datasheet" "https://www.farnell.com/datasheets/1641674.pdf"
				(at 25.4 -15.24 0)
				(effects
					(font
						(size 1.27 1.27)
						(thickness 0.15)
					)
					(justify left bottom)
					(hide yes)
				)
			)
			(property "Description" "Push-Pull Output Comparator, 1,6V to 5.5V, SOT-23-5"
				(at 0 0 0)
				(effects
					(font
						(size 1.27 1.27)
					)
					(hide yes)
				)
			)
			(property "MPN" "MCP6541T-E/OT"
				(at 25.4 -7.62 0)
				(effects
					(font
						(size 1.27 1.27)
						(thickness 0.15)
					)
					(justify left bottom)
				)
			)
			(property "Manufacturer" "Microchip Technology"
				(at 25.4 -17.78 0)
				(effects
					(font
						(size 1.27 1.27)
						(thickness 0.15)
					)
					(justify left bottom)
					(hide yes)
				)
			)
			(property "Author" "Antmicro"
				(at 25.4 -20.32 0)
				(effects
					(font
						(size 1.27 1.27)
						(thickness 0.15)
					)
					(justify left bottom)
					(hide yes)
				)
			)
			(property "License" "Apache-2.0"
				(at 25.4 -22.86 0)
				(effects
					(font
						(size 1.27 1.27)
						(thickness 0.15)
					)
					(justify left bottom)
					(hide yes)
				)
			)
			(property "ki_locked" ""
				(at 0 0 0)
				(effects
					(font
						(size 1.27 1.27)
					)
				)
			)
			(property "ki_keywords" "SMT,  IC"
				(at 0 0 0)
				(effects
					(font
						(size 1.27 1.27)
					)
					(hide yes)
				)
			)
			(symbol "MCP6541_SOT23-5_1_1"
				(polyline
					(pts
						(xy 4.953 -1.27) (xy 4.826 -1.27)
					)
					(stroke
						(width 0.127)
						(type default)
					)
					(fill
						(type background)
					)
				)
				(polyline
					(pts
						(xy 5.461 -1.27) (xy 5.207 -1.27)
					)
					(stroke
						(width 0.127)
						(type default)
					)
					(fill
						(type background)
					)
				)
				(polyline
					(pts
						(xy 5.842 -1.27) (xy 5.715 -1.27)
					)
					(stroke
						(width 0.127)
						(type default)
					)
					(fill
						(type background)
					)
				)
				(polyline
					(pts
						(xy 2.54 1.27) (xy 7.62 -1.27) (xy 2.54 -3.81) (xy 2.54 1.27)
					)
					(stroke
						(width 0.254)
						(type default)
					)
					(fill
						(type background)
					)
				)
				(polyline
					(pts
						(xy 4.826 -1.778) (xy 5.207 -1.778) (xy 5.461 -0.762) (xy 5.842 -0.762)
					)
					(stroke
						(width 0.127)
						(type default)
					)
					(fill
						(type background)
					)
				)
				(text "+"
					(at 2.54 -1.016 0)
					(effects
						(font
							(size 1.27 1.27)
							(thickness 0.15)
						)
						(justify left bottom)
					)
				)
				(text "-"
					(at 2.54 -3.302 0)
					(effects
						(font
							(size 1.27 1.27)
							(thickness 0.15)
						)
						(justify left bottom)
					)
				)
				(pin output line
					(at 10.16 -1.27 180)
					(length 2.54)
					(name ""
						(effects
							(font
								(size 1.27 1.27)
							)
						)
					)
					(number "1"
						(effects
							(font
								(size 1.27 1.27)
							)
						)
					)
				)
				(pin input line
					(at 0 0 0)
					(length 2.54)
					(name ""
						(effects
							(font
								(size 1.27 1.27)
							)
						)
					)
					(number "3"
						(effects
							(font
								(size 1.27 1.27)
							)
						)
					)
				)
				(pin input line
					(at 0 -2.54 0)
					(length 2.54)
					(name ""
						(effects
							(font
								(size 1.27 1.27)
							)
						)
					)
					(number "4"
						(effects
							(font
								(size 1.27 1.27)
							)
						)
					)
				)
			)
			(symbol "MCP6541_SOT23-5_2_1"
				(rectangle
					(start 2.54 1.27)
					(end 7.62 -3.81)
					(stroke
						(width 0.254)
						(type default)
					)
					(fill
						(type background)
					)
				)
				(pin power_in line
					(at 0 -2.54 0)
					(length 2.54)
					(name "VSS"
						(effects
							(font
								(size 1.27 1.27)
							)
						)
					)
					(number "2"
						(effects
							(font
								(size 1.27 1.27)
							)
						)
					)
				)
				(pin power_in line
					(at 0 0 0)
					(length 2.54)
					(name "VDD"
						(effects
							(font
								(size 1.27 1.27)
							)
						)
					)
					(number "5"
						(effects
							(font
								(size 1.27 1.27)
							)
						)
					)
				)
			)
		)
	(symbol "antmicroPMICMotorDriversControllers:MAX6643_QSOP"
			(exclude_from_sim no)
			(in_bom yes)
			(on_board yes)
			(property "Reference" "U"
				(at 38.1 -2.54 0)
				(effects
					(font
						(size 1.27 1.27)
						(thickness 0.15)
					)
					(justify left bottom)
				)
			)
			(property "Value" "MAX6643_QSOP"
				(at 38.1 -7.62 0)
				(effects
					(font
						(size 1.27 1.27)
						(thickness 0.15)
					)
					(justify left bottom)
					(hide yes)
				)
			)
			(property "Footprint" "antmicro-footprints:QSOP-16_3x4.75x0.75mm_P0.5mm"
				(at 38.1 -10.16 0)
				(effects
					(font
						(size 1.27 1.27)
						(thickness 0.15)
					)
					(justify left bottom)
					(hide yes)
				)
			)
			(property "Datasheet" "https://www.analog.com/media/en/technical-documentation/data-sheets/MAX6643-MAX6645.pdf"
				(at 38.1 -12.7 0)
				(effects
					(font
						(size 1.27 1.27)
						(thickness 0.15)
					)
					(justify left bottom)
					(hide yes)
				)
			)
			(property "Description" "PWM Controller, Overtemperature Output, 3V to 5.5V Supply, 32Hz, QSOP-16"
				(at 0 0 0)
				(effects
					(font
						(size 1.27 1.27)
					)
					(hide yes)
				)
			)
			(property "Manufacturer" "Analog Devices"
				(at 38.1 -15.24 0)
				(effects
					(font
						(size 1.27 1.27)
						(thickness 0.15)
					)
					(justify left bottom)
					(hide yes)
				)
			)
			(property "MPN" "MAX6643LBBAEE+"
				(at 38.1 -5.08 0)
				(effects
					(font
						(size 1.27 1.27)
						(thickness 0.15)
					)
					(justify left bottom)
				)
			)
			(property "Author" "Antmicro"
				(at 38.1 -17.78 0)
				(effects
					(font
						(size 1.27 1.27)
						(thickness 0.15)
					)
					(justify left bottom)
					(hide yes)
				)
			)
			(property "License" "Apache-2.0"
				(at 38.1 -20.32 0)
				(effects
					(font
						(size 1.27 1.27)
						(thickness 0.15)
					)
					(justify left bottom)
					(hide yes)
				)
			)
			(property "ki_keywords" "CONTROLLER"
				(at 0 0 0)
				(effects
					(font
						(size 1.27 1.27)
					)
					(hide yes)
				)
			)
			(symbol "MAX6643_QSOP_1_1"
				(rectangle
					(start 2.54 2.54)
					(end 21.59 -30.48)
					(stroke
						(width 0.254)
						(type default)
					)
					(fill
						(type background)
					)
				)
				(pin input line
					(at 0 -12.7 0)
					(length 2.54)
					(name "TH1"
						(effects
							(font
								(size 1.27 1.27)
							)
						)
					)
					(number "1"
						(effects
							(font
								(size 1.27 1.27)
							)
						)
					)
				)
				(pin input line
					(at 0 -10.16 0)
					(length 2.54)
					(name "FAN_IN2"
						(effects
							(font
								(size 1.27 1.27)
							)
						)
					)
					(number "10"
						(effects
							(font
								(size 1.27 1.27)
							)
						)
					)
				)
				(pin input line
					(at 0 -7.62 0)
					(length 2.54)
					(name "FAN_IN1"
						(effects
							(font
								(size 1.27 1.27)
							)
						)
					)
					(number "11"
						(effects
							(font
								(size 1.27 1.27)
							)
						)
					)
				)
				(pin output line
					(at 24.13 0 180)
					(length 2.54)
					(name "PWM_OUT"
						(effects
							(font
								(size 1.27 1.27)
							)
						)
					)
					(number "12"
						(effects
							(font
								(size 1.27 1.27)
							)
						)
					)
				)
				(pin input line
					(at 0 -25.4 0)
					(length 2.54)
					(name "OT2"
						(effects
							(font
								(size 1.27 1.27)
							)
						)
					)
					(number "13"
						(effects
							(font
								(size 1.27 1.27)
							)
						)
					)
				)
				(pin input line
					(at 0 -22.86 0)
					(length 2.54)
					(name "OT1"
						(effects
							(font
								(size 1.27 1.27)
							)
						)
					)
					(number "14"
						(effects
							(font
								(size 1.27 1.27)
							)
						)
					)
				)
				(pin input line
					(at 0 -15.24 0)
					(length 2.54)
					(name "TH2"
						(effects
							(font
								(size 1.27 1.27)
							)
						)
					)
					(number "15"
						(effects
							(font
								(size 1.27 1.27)
							)
						)
					)
				)
				(pin power_in line
					(at 0 0 0)
					(length 2.54)
					(name "VDD"
						(effects
							(font
								(size 1.27 1.27)
							)
						)
					)
					(number "16"
						(effects
							(font
								(size 1.27 1.27)
							)
						)
					)
				)
				(pin input line
					(at 0 -20.32 0)
					(length 2.54)
					(name "TL2"
						(effects
							(font
								(size 1.27 1.27)
							)
						)
					)
					(number "2"
						(effects
							(font
								(size 1.27 1.27)
							)
						)
					)
				)
				(pin input line
					(at 0 -17.78 0)
					(length 2.54)
					(name "TL1"
						(effects
							(font
								(size 1.27 1.27)
							)
						)
					)
					(number "3"
						(effects
							(font
								(size 1.27 1.27)
							)
						)
					)
				)
				(pin output line
					(at 24.13 -5.08 180)
					(length 2.54)
					(name "~{FANFAIL}"
						(effects
							(font
								(size 1.27 1.27)
							)
						)
					)
					(number "4"
						(effects
							(font
								(size 1.27 1.27)
							)
						)
					)
				)
				(pin input line
					(at 0 -2.54 0)
					(length 2.54)
					(name "TACHSET"
						(effects
							(font
								(size 1.27 1.27)
							)
						)
					)
					(number "5"
						(effects
							(font
								(size 1.27 1.27)
							)
						)
					)
				)
				(pin input line
					(at 0 -5.08 0)
					(length 2.54)
					(name "FULLSPD"
						(effects
							(font
								(size 1.27 1.27)
							)
						)
					)
					(number "6"
						(effects
							(font
								(size 1.27 1.27)
							)
						)
					)
				)
				(pin power_in line
					(at 24.13 -27.94 180)
					(length 2.54)
					(name "GND"
						(effects
							(font
								(size 1.27 1.27)
							)
						)
					)
					(number "7"
						(effects
							(font
								(size 1.27 1.27)
							)
						)
					)
				)
				(pin input line
					(at 0 -27.94 0)
					(length 2.54)
					(name "DXP"
						(effects
							(font
								(size 1.27 1.27)
							)
						)
					)
					(number "8"
						(effects
							(font
								(size 1.27 1.27)
							)
						)
					)
				)
				(pin output line
					(at 24.13 -2.54 180)
					(length 2.54)
					(name "~{OT}"
						(effects
							(font
								(size 1.27 1.27)
							)
						)
					)
					(number "9"
						(effects
							(font
								(size 1.27 1.27)
							)
						)
					)
				)
			)
		)
	(symbol "antmicroPMICORControllersIdealDiodes:DZDH0401DW"
			(exclude_from_sim no)
			(in_bom yes)
			(on_board yes)
			(property "Reference" "Q"
				(at 30.48 -5.08 0)
				(effects
					(font
						(size 1.27 1.27)
						(thickness 0.15)
					)
					(justify left bottom)
				)
			)
			(property "Value" "DZDH0401DW"
				(at 30.48 -7.62 0)
				(effects
					(font
						(size 1.27 1.27)
						(thickness 0.15)
					)
					(justify left bottom)
					(hide yes)
				)
			)
			(property "Footprint" "antmicro-footprints:SOT-363"
				(at 30.48 -10.16 0)
				(effects
					(font
						(size 1.27 1.27)
						(thickness 0.15)
					)
					(justify left bottom)
					(hide yes)
				)
			)
			(property "Datasheet" "https://www.mouser.com/datasheet/2/115/DIOD_S_A0011803041_1-2543705.pdf"
				(at 30.48 -12.7 0)
				(effects
					(font
						(size 1.27 1.27)
						(thickness 0.15)
					)
					(justify left bottom)
					(hide yes)
				)
			)
			(property "Description" "OR Controller N+1 ORing Controller P-Channel 1:1 SOT-363"
				(at 0 0 0)
				(effects
					(font
						(size 1.27 1.27)
					)
					(hide yes)
				)
			)
			(property "MPN" "DZDH0401DW"
				(at 30.48 -15.24 0)
				(effects
					(font
						(size 1.27 1.27)
						(thickness 0.15)
					)
					(justify left bottom)
				)
			)
			(property "Manufacturer" "Diodes Incorporated"
				(at 30.48 -17.78 0)
				(effects
					(font
						(size 1.27 1.27)
						(thickness 0.15)
					)
					(justify left bottom)
					(hide yes)
				)
			)
			(property "Author" "Antmicro"
				(at 30.48 -20.32 0)
				(effects
					(font
						(size 1.27 1.27)
						(thickness 0.15)
					)
					(justify left bottom)
					(hide yes)
				)
			)
			(property "License" "Apache-2.0"
				(at 30.48 -22.86 0)
				(effects
					(font
						(size 1.27 1.27)
						(thickness 0.15)
					)
					(justify left bottom)
					(hide yes)
				)
			)
			(property "ki_keywords" "SMT, CONTROLLER, SEMICONDUCTOR, DIODE, PMOS"
				(at 0 0 0)
				(effects
					(font
						(size 1.27 1.27)
					)
					(hide yes)
				)
			)
			(symbol "DZDH0401DW_1_1"
				(rectangle
					(start 2.54 1.905)
					(end 13.97 -4.445)
					(stroke
						(width 0.254)
						(type default)
					)
					(fill
						(type background)
					)
				)
				(pin input line
					(at 0 -2.54 0)
					(length 2.54)
					(name "REF"
						(effects
							(font
								(size 1.27 1.27)
							)
						)
					)
					(number "2"
						(effects
							(font
								(size 1.27 1.27)
							)
						)
					)
				)
				(pin output line
					(at 16.51 -2.54 180)
					(length 2.54)
					(name "BIAS"
						(effects
							(font
								(size 1.27 1.27)
							)
						)
					)
					(number "3"
						(effects
							(font
								(size 1.27 1.27)
							)
						)
					)
				)
				(pin power_in line
					(at 16.51 0 180)
					(length 2.54)
					(name "S"
						(effects
							(font
								(size 1.27 1.27)
							)
						)
					)
					(number "4"
						(effects
							(font
								(size 1.27 1.27)
							)
						)
					)
				)
				(pin power_in line
					(at 0 0 0)
					(length 2.54)
					(name "D"
						(effects
							(font
								(size 1.27 1.27)
							)
						)
					)
					(number "6"
						(effects
							(font
								(size 1.27 1.27)
							)
						)
					)
				)
			)
		)
	(symbol "antmicroPMICPowerDistributionSwitchesLoadDrivers:AP22615A_TSOT26"
			(exclude_from_sim no)
			(in_bom yes)
			(on_board yes)
			(property "Reference" "U"
				(at 30.48 -2.54 0)
				(effects
					(font
						(size 1.27 1.27)
						(thickness 0.15)
					)
					(justify left bottom)
				)
			)
			(property "Value" "AP22615A_TSOT26"
				(at 30.48 -5.08 0)
				(effects
					(font
						(size 1.27 1.27)
						(thickness 0.15)
					)
					(justify left bottom)
					(hide yes)
				)
			)
			(property "Footprint" "antmicro-footprints:TSOT23-6"
				(at 30.48 -7.62 0)
				(effects
					(font
						(size 1.27 1.27)
						(thickness 0.15)
					)
					(justify left bottom)
					(hide yes)
				)
			)
			(property "Datasheet" "https://www.mouser.com/datasheet/2/115/DIOD_S_A0008958405_1-2543193.pdf"
				(at 30.48 -10.16 0)
				(effects
					(font
						(size 1.27 1.27)
						(thickness 0.15)
					)
					(justify left bottom)
					(hide yes)
				)
			)
			(property "Description" "Power Load Distribution Switch, High Side, Active High, 1 Output, 5.5 V, 3.6 A, 0.04 ohm, TSOT-26-6"
				(at 0 0 0)
				(effects
					(font
						(size 1.27 1.27)
					)
					(hide yes)
				)
			)
			(property "MPN" "AP22615AWU-7"
				(at 30.48 -12.7 0)
				(effects
					(font
						(size 1.27 1.27)
						(thickness 0.15)
					)
					(justify left bottom)
				)
			)
			(property "Manufacturer" "Diodes Incorporated"
				(at 30.48 -15.24 0)
				(effects
					(font
						(size 1.27 1.27)
						(thickness 0.15)
					)
					(justify left bottom)
					(hide yes)
				)
			)
			(property "Author" "Antmicro"
				(at 30.48 -17.78 0)
				(effects
					(font
						(size 1.27 1.27)
						(thickness 0.15)
					)
					(justify left bottom)
					(hide yes)
				)
			)
			(property "License" "Apache-2.0"
				(at 30.48 -20.32 0)
				(effects
					(font
						(size 1.27 1.27)
						(thickness 0.15)
					)
					(justify left bottom)
					(hide yes)
				)
			)
			(property "ki_keywords" "SMT, PMIC, IC, VOLTAGE"
				(at 0 0 0)
				(effects
					(font
						(size 1.27 1.27)
					)
					(hide yes)
				)
			)
			(symbol "AP22615A_TSOT26_1_1"
				(rectangle
					(start 2.54 2.54)
					(end 12.7 -7.62)
					(stroke
						(width 0.254)
						(type default)
					)
					(fill
						(type background)
					)
				)
				(pin power_out line
					(at 15.24 0 180)
					(length 2.54)
					(name "OUT"
						(effects
							(font
								(size 1.27 1.27)
							)
						)
					)
					(number "1"
						(effects
							(font
								(size 1.27 1.27)
							)
						)
					)
				)
				(pin power_in line
					(at 15.24 -5.08 180)
					(length 2.54)
					(name "GND"
						(effects
							(font
								(size 1.27 1.27)
							)
						)
					)
					(number "2"
						(effects
							(font
								(size 1.27 1.27)
							)
						)
					)
				)
				(pin output line
					(at 0 -2.54 0)
					(length 2.54)
					(name "FLG"
						(effects
							(font
								(size 1.27 1.27)
							)
						)
					)
					(number "3"
						(effects
							(font
								(size 1.27 1.27)
							)
						)
					)
				)
				(pin input line
					(at 0 -5.08 0)
					(length 2.54)
					(name "EN"
						(effects
							(font
								(size 1.27 1.27)
							)
						)
					)
					(number "4"
						(effects
							(font
								(size 1.27 1.27)
							)
						)
					)
				)
				(pin passive line
					(at 15.24 -2.54 180)
					(length 2.54)
					(name "ISET"
						(effects
							(font
								(size 1.27 1.27)
							)
						)
					)
					(number "5"
						(effects
							(font
								(size 1.27 1.27)
							)
						)
					)
				)
				(pin power_in line
					(at 0 0 0)
					(length 2.54)
					(name "IN"
						(effects
							(font
								(size 1.27 1.27)
							)
						)
					)
					(number "6"
						(effects
							(font
								(size 1.27 1.27)
							)
						)
					)
				)
			)
		)
	(symbol "antmicroPMICVoltageRegulatorsLinear:LM1117MP-3.3_NOPB"
			(exclude_from_sim no)
			(in_bom yes)
			(on_board yes)
			(property "Reference" "U"
				(at 33.02 -2.54 0)
				(effects
					(font
						(size 1.27 1.27)
						(thickness 0.15)
					)
					(justify left bottom)
				)
			)
			(property "Value" "LM1117MP-3.3_NOPB"
				(at 33.02 -7.62 0)
				(effects
					(font
						(size 1.27 1.27)
						(thickness 0.15)
					)
					(justify left bottom)
					(hide yes)
				)
			)
			(property "Footprint" "antmicro-footprints:SOT-223"
				(at 33.02 -10.16 0)
				(effects
					(font
						(size 1.27 1.27)
						(thickness 0.15)
					)
					(justify left bottom)
					(hide yes)
				)
			)
			(property "Datasheet" "https://www.ti.com/lit/ds/symlink/lm1117.pdf?ts=1695352253515&ref_url=https%253A%252F%252Fwww.google.com%252F"
				(at 33.02 -12.7 0)
				(effects
					(font
						(size 1.27 1.27)
						(thickness 0.15)
					)
					(justify left bottom)
					(hide yes)
				)
			)
			(property "Description" "IC REG LINEAR 3.3V 800MA SOT223"
				(at 0 0 0)
				(effects
					(font
						(size 1.27 1.27)
					)
					(hide yes)
				)
			)
			(property "Author" "Antmicro"
				(at 33.02 -15.24 0)
				(effects
					(font
						(size 1.27 1.27)
						(thickness 0.15)
					)
					(justify left bottom)
					(hide yes)
				)
			)
			(property "License" "Apache-2.0"
				(at 33.02 -17.78 0)
				(effects
					(font
						(size 1.27 1.27)
						(thickness 0.15)
					)
					(justify left bottom)
					(hide yes)
				)
			)
			(property "MPN" "LM1117IMP-3.3/NOPB"
				(at 33.02 -5.08 0)
				(effects
					(font
						(size 1.27 1.27)
						(thickness 0.15)
					)
					(justify left bottom)
				)
			)
			(property "Manufacturer" "Texas Instruments"
				(at 33.02 -20.32 0)
				(effects
					(font
						(size 1.27 1.27)
						(thickness 0.15)
					)
					(justify left bottom)
					(hide yes)
				)
			)
			(property "ki_keywords" "SMT, REGULATOR, IC, LINEAR"
				(at 0 0 0)
				(effects
					(font
						(size 1.27 1.27)
					)
					(hide yes)
				)
			)
			(symbol "LM1117MP-3.3_NOPB_1_1"
				(rectangle
					(start 2.54 2.54)
					(end 15.24 -5.08)
					(stroke
						(width 0.254)
						(type default)
					)
					(fill
						(type background)
					)
				)
				(pin power_in line
					(at 0 -2.54 0)
					(length 2.54)
					(name "ADJ/GND"
						(effects
							(font
								(size 1.27 1.27)
							)
						)
					)
					(number "1"
						(effects
							(font
								(size 1.27 1.27)
							)
						)
					)
				)
				(pin output line
					(at 17.78 0 180)
					(length 2.54)
					(name "VOUT"
						(effects
							(font
								(size 1.27 1.27)
							)
						)
					)
					(number "2"
						(effects
							(font
								(size 1.27 1.27)
							)
						)
					)
				)
				(pin input line
					(at 0 0 0)
					(length 2.54)
					(name "VIN"
						(effects
							(font
								(size 1.27 1.27)
							)
						)
					)
					(number "3"
						(effects
							(font
								(size 1.27 1.27)
							)
						)
					)
				)
				(pin output line
					(at 17.78 0 180)
					(length 2.54) hide
					(name "VOUT"
						(effects
							(font
								(size 1.27 1.27)
							)
						)
					)
					(number "4"
						(effects
							(font
								(size 1.27 1.27)
							)
						)
					)
				)
			)
		)
	(symbol "antmicroPciConnectors:PCIe_x16_10146070-113Y0LF-vertical"
			(exclude_from_sim no)
			(in_bom yes)
			(on_board yes)
			(property "Reference" "J"
				(at 35.56 -2.54 0)
				(effects
					(font
						(size 1.27 1.27)
						(thickness 0.15)
					)
					(justify left bottom)
				)
			)
			(property "Value" "PCIe_x16_10146070-113Y0LF-vertical"
				(at 35.56 -5.08 0)
				(effects
					(font
						(size 1.27 1.27)
						(thickness 0.15)
					)
					(justify left bottom)
					(hide yes)
				)
			)
			(property "Footprint" "antmicro-footprints:AMPHENOL_10146070-113Y0LF"
				(at 35.56 -7.62 0)
				(effects
					(font
						(size 1.27 1.27)
						(thickness 0.15)
					)
					(justify left bottom)
					(hide yes)
				)
			)
			(property "Datasheet" "https://www.farnell.com/datasheets/3212936.pdf"
				(at 35.56 -10.16 0)
				(effects
					(font
						(size 1.27 1.27)
						(thickness 0.15)
					)
					(justify left bottom)
					(hide yes)
				)
			)
			(property "Description" "164 Position Female Connector PCI Express™ Gold 0.039\" (1.00mm) Black"
				(at 0 0 0)
				(effects
					(font
						(size 1.27 1.27)
					)
					(hide yes)
				)
			)
			(property "PARTREV" "E"
				(at 35.56 -12.7 0)
				(effects
					(font
						(size 1.27 1.27)
						(thickness 0.15)
					)
					(justify left bottom)
					(hide yes)
				)
			)
			(property "STANDARD" "Manufacturer Recommendations"
				(at 35.56 -15.24 0)
				(effects
					(font
						(size 1.27 1.27)
						(thickness 0.15)
					)
					(justify left bottom)
					(hide yes)
				)
			)
			(property "MAXIMUM_PACKAGE_HEIGHT" "11.25mm"
				(at 35.56 -17.78 0)
				(effects
					(font
						(size 1.27 1.27)
						(thickness 0.15)
					)
					(justify left bottom)
					(hide yes)
				)
			)
			(property "Manufacturer" "Amphenol"
				(at 35.56 -20.32 0)
				(effects
					(font
						(size 1.27 1.27)
						(thickness 0.15)
					)
					(justify left bottom)
					(hide yes)
				)
			)
			(property "Author" "Antmicro"
				(at 35.56 -22.86 0)
				(effects
					(font
						(size 1.27 1.27)
						(thickness 0.15)
					)
					(justify left bottom)
					(hide yes)
				)
			)
			(property "License" "Apache-2.0"
				(at 35.56 -25.4 0)
				(effects
					(font
						(size 1.27 1.27)
						(thickness 0.15)
					)
					(justify left bottom)
					(hide yes)
				)
			)
			(property "MPN" "10146070-113Y0LF"
				(at 35.56 -27.94 0)
				(effects
					(font
						(size 1.27 1.27)
						(thickness 0.15)
					)
					(justify left bottom)
				)
			)
			(property "ki_keywords" "CONNECTOR"
				(at 0 0 0)
				(effects
					(font
						(size 1.27 1.27)
					)
					(hide yes)
				)
			)
			(symbol "PCIe_x16_10146070-113Y0LF-vertical_1_1"
				(rectangle
					(start 3.81 -104.14)
					(end 19.05 2.54)
					(stroke
						(width 0.254)
						(type default)
					)
					(fill
						(type background)
					)
				)
				(pin passive line
					(at 22.86 0 180)
					(length 3.81)
					(name "A1"
						(effects
							(font
								(size 1.27 1.27)
							)
						)
					)
					(number "A1"
						(effects
							(font
								(size 1.27 1.27)
							)
						)
					)
				)
				(pin passive line
					(at 22.86 -22.86 180)
					(length 3.81)
					(name "A10"
						(effects
							(font
								(size 1.27 1.27)
							)
						)
					)
					(number "A10"
						(effects
							(font
								(size 1.27 1.27)
							)
						)
					)
				)
				(pin passive line
					(at 22.86 -25.4 180)
					(length 3.81)
					(name "A11"
						(effects
							(font
								(size 1.27 1.27)
							)
						)
					)
					(number "A11"
						(effects
							(font
								(size 1.27 1.27)
							)
						)
					)
				)
				(pin passive line
					(at 22.86 -27.94 180)
					(length 3.81)
					(name "A12"
						(effects
							(font
								(size 1.27 1.27)
							)
						)
					)
					(number "A12"
						(effects
							(font
								(size 1.27 1.27)
							)
						)
					)
				)
				(pin passive line
					(at 22.86 -30.48 180)
					(length 3.81)
					(name "A13"
						(effects
							(font
								(size 1.27 1.27)
							)
						)
					)
					(number "A13"
						(effects
							(font
								(size 1.27 1.27)
							)
						)
					)
				)
				(pin passive line
					(at 22.86 -33.02 180)
					(length 3.81)
					(name "A14"
						(effects
							(font
								(size 1.27 1.27)
							)
						)
					)
					(number "A14"
						(effects
							(font
								(size 1.27 1.27)
							)
						)
					)
				)
				(pin passive line
					(at 22.86 -35.56 180)
					(length 3.81)
					(name "A15"
						(effects
							(font
								(size 1.27 1.27)
							)
						)
					)
					(number "A15"
						(effects
							(font
								(size 1.27 1.27)
							)
						)
					)
				)
				(pin passive line
					(at 22.86 -38.1 180)
					(length 3.81)
					(name "A16"
						(effects
							(font
								(size 1.27 1.27)
							)
						)
					)
					(number "A16"
						(effects
							(font
								(size 1.27 1.27)
							)
						)
					)
				)
				(pin passive line
					(at 22.86 -40.64 180)
					(length 3.81)
					(name "A17"
						(effects
							(font
								(size 1.27 1.27)
							)
						)
					)
					(number "A17"
						(effects
							(font
								(size 1.27 1.27)
							)
						)
					)
				)
				(pin passive line
					(at 22.86 -43.18 180)
					(length 3.81)
					(name "A18"
						(effects
							(font
								(size 1.27 1.27)
							)
						)
					)
					(number "A18"
						(effects
							(font
								(size 1.27 1.27)
							)
						)
					)
				)
				(pin passive line
					(at 22.86 -45.72 180)
					(length 3.81)
					(name "A19"
						(effects
							(font
								(size 1.27 1.27)
							)
						)
					)
					(number "A19"
						(effects
							(font
								(size 1.27 1.27)
							)
						)
					)
				)
				(pin passive line
					(at 22.86 -2.54 180)
					(length 3.81)
					(name "A2"
						(effects
							(font
								(size 1.27 1.27)
							)
						)
					)
					(number "A2"
						(effects
							(font
								(size 1.27 1.27)
							)
						)
					)
				)
				(pin passive line
					(at 22.86 -48.26 180)
					(length 3.81)
					(name "A20"
						(effects
							(font
								(size 1.27 1.27)
							)
						)
					)
					(number "A20"
						(effects
							(font
								(size 1.27 1.27)
							)
						)
					)
				)
				(pin passive line
					(at 22.86 -50.8 180)
					(length 3.81)
					(name "A21"
						(effects
							(font
								(size 1.27 1.27)
							)
						)
					)
					(number "A21"
						(effects
							(font
								(size 1.27 1.27)
							)
						)
					)
				)
				(pin passive line
					(at 22.86 -53.34 180)
					(length 3.81)
					(name "A22"
						(effects
							(font
								(size 1.27 1.27)
							)
						)
					)
					(number "A22"
						(effects
							(font
								(size 1.27 1.27)
							)
						)
					)
				)
				(pin passive line
					(at 22.86 -55.88 180)
					(length 3.81)
					(name "A23"
						(effects
							(font
								(size 1.27 1.27)
							)
						)
					)
					(number "A23"
						(effects
							(font
								(size 1.27 1.27)
							)
						)
					)
				)
				(pin passive line
					(at 22.86 -58.42 180)
					(length 3.81)
					(name "A24"
						(effects
							(font
								(size 1.27 1.27)
							)
						)
					)
					(number "A24"
						(effects
							(font
								(size 1.27 1.27)
							)
						)
					)
				)
				(pin passive line
					(at 22.86 -60.96 180)
					(length 3.81)
					(name "A25"
						(effects
							(font
								(size 1.27 1.27)
							)
						)
					)
					(number "A25"
						(effects
							(font
								(size 1.27 1.27)
							)
						)
					)
				)
				(pin passive line
					(at 22.86 -63.5 180)
					(length 3.81)
					(name "A26"
						(effects
							(font
								(size 1.27 1.27)
							)
						)
					)
					(number "A26"
						(effects
							(font
								(size 1.27 1.27)
							)
						)
					)
				)
				(pin passive line
					(at 22.86 -66.04 180)
					(length 3.81)
					(name "A27"
						(effects
							(font
								(size 1.27 1.27)
							)
						)
					)
					(number "A27"
						(effects
							(font
								(size 1.27 1.27)
							)
						)
					)
				)
				(pin passive line
					(at 22.86 -68.58 180)
					(length 3.81)
					(name "A28"
						(effects
							(font
								(size 1.27 1.27)
							)
						)
					)
					(number "A28"
						(effects
							(font
								(size 1.27 1.27)
							)
						)
					)
				)
				(pin passive line
					(at 22.86 -71.12 180)
					(length 3.81)
					(name "A29"
						(effects
							(font
								(size 1.27 1.27)
							)
						)
					)
					(number "A29"
						(effects
							(font
								(size 1.27 1.27)
							)
						)
					)
				)
				(pin passive line
					(at 22.86 -5.08 180)
					(length 3.81)
					(name "A3"
						(effects
							(font
								(size 1.27 1.27)
							)
						)
					)
					(number "A3"
						(effects
							(font
								(size 1.27 1.27)
							)
						)
					)
				)
				(pin passive line
					(at 22.86 -73.66 180)
					(length 3.81)
					(name "A30"
						(effects
							(font
								(size 1.27 1.27)
							)
						)
					)
					(number "A30"
						(effects
							(font
								(size 1.27 1.27)
							)
						)
					)
				)
				(pin passive line
					(at 22.86 -76.2 180)
					(length 3.81)
					(name "A31"
						(effects
							(font
								(size 1.27 1.27)
							)
						)
					)
					(number "A31"
						(effects
							(font
								(size 1.27 1.27)
							)
						)
					)
				)
				(pin passive line
					(at 22.86 -78.74 180)
					(length 3.81)
					(name "A32"
						(effects
							(font
								(size 1.27 1.27)
							)
						)
					)
					(number "A32"
						(effects
							(font
								(size 1.27 1.27)
							)
						)
					)
				)
				(pin passive line
					(at 22.86 -81.28 180)
					(length 3.81)
					(name "A33"
						(effects
							(font
								(size 1.27 1.27)
							)
						)
					)
					(number "A33"
						(effects
							(font
								(size 1.27 1.27)
							)
						)
					)
				)
				(pin passive line
					(at 22.86 -83.82 180)
					(length 3.81)
					(name "A34"
						(effects
							(font
								(size 1.27 1.27)
							)
						)
					)
					(number "A34"
						(effects
							(font
								(size 1.27 1.27)
							)
						)
					)
				)
				(pin passive line
					(at 22.86 -86.36 180)
					(length 3.81)
					(name "A35"
						(effects
							(font
								(size 1.27 1.27)
							)
						)
					)
					(number "A35"
						(effects
							(font
								(size 1.27 1.27)
							)
						)
					)
				)
				(pin passive line
					(at 22.86 -88.9 180)
					(length 3.81)
					(name "A36"
						(effects
							(font
								(size 1.27 1.27)
							)
						)
					)
					(number "A36"
						(effects
							(font
								(size 1.27 1.27)
							)
						)
					)
				)
				(pin passive line
					(at 22.86 -91.44 180)
					(length 3.81)
					(name "A37"
						(effects
							(font
								(size 1.27 1.27)
							)
						)
					)
					(number "A37"
						(effects
							(font
								(size 1.27 1.27)
							)
						)
					)
				)
				(pin passive line
					(at 22.86 -93.98 180)
					(length 3.81)
					(name "A38"
						(effects
							(font
								(size 1.27 1.27)
							)
						)
					)
					(number "A38"
						(effects
							(font
								(size 1.27 1.27)
							)
						)
					)
				)
				(pin passive line
					(at 22.86 -96.52 180)
					(length 3.81)
					(name "A39"
						(effects
							(font
								(size 1.27 1.27)
							)
						)
					)
					(number "A39"
						(effects
							(font
								(size 1.27 1.27)
							)
						)
					)
				)
				(pin passive line
					(at 22.86 -7.62 180)
					(length 3.81)
					(name "A4"
						(effects
							(font
								(size 1.27 1.27)
							)
						)
					)
					(number "A4"
						(effects
							(font
								(size 1.27 1.27)
							)
						)
					)
				)
				(pin passive line
					(at 22.86 -99.06 180)
					(length 3.81)
					(name "A40"
						(effects
							(font
								(size 1.27 1.27)
							)
						)
					)
					(number "A40"
						(effects
							(font
								(size 1.27 1.27)
							)
						)
					)
				)
				(pin passive line
					(at 22.86 -101.6 180)
					(length 3.81)
					(name "A41"
						(effects
							(font
								(size 1.27 1.27)
							)
						)
					)
					(number "A41"
						(effects
							(font
								(size 1.27 1.27)
							)
						)
					)
				)
				(pin passive line
					(at 22.86 -10.16 180)
					(length 3.81)
					(name "A5"
						(effects
							(font
								(size 1.27 1.27)
							)
						)
					)
					(number "A5"
						(effects
							(font
								(size 1.27 1.27)
							)
						)
					)
				)
				(pin passive line
					(at 22.86 -12.7 180)
					(length 3.81)
					(name "A6"
						(effects
							(font
								(size 1.27 1.27)
							)
						)
					)
					(number "A6"
						(effects
							(font
								(size 1.27 1.27)
							)
						)
					)
				)
				(pin passive line
					(at 22.86 -15.24 180)
					(length 3.81)
					(name "A7"
						(effects
							(font
								(size 1.27 1.27)
							)
						)
					)
					(number "A7"
						(effects
							(font
								(size 1.27 1.27)
							)
						)
					)
				)
				(pin passive line
					(at 22.86 -17.78 180)
					(length 3.81)
					(name "A8"
						(effects
							(font
								(size 1.27 1.27)
							)
						)
					)
					(number "A8"
						(effects
							(font
								(size 1.27 1.27)
							)
						)
					)
				)
				(pin passive line
					(at 22.86 -20.32 180)
					(length 3.81)
					(name "A9"
						(effects
							(font
								(size 1.27 1.27)
							)
						)
					)
					(number "A9"
						(effects
							(font
								(size 1.27 1.27)
							)
						)
					)
				)
				(pin passive line
					(at 0 0 0)
					(length 3.81)
					(name "B1"
						(effects
							(font
								(size 1.27 1.27)
							)
						)
					)
					(number "B1"
						(effects
							(font
								(size 1.27 1.27)
							)
						)
					)
				)
				(pin passive line
					(at 0 -22.86 0)
					(length 3.81)
					(name "B10"
						(effects
							(font
								(size 1.27 1.27)
							)
						)
					)
					(number "B10"
						(effects
							(font
								(size 1.27 1.27)
							)
						)
					)
				)
				(pin passive line
					(at 0 -25.4 0)
					(length 3.81)
					(name "B11"
						(effects
							(font
								(size 1.27 1.27)
							)
						)
					)
					(number "B11"
						(effects
							(font
								(size 1.27 1.27)
							)
						)
					)
				)
				(pin passive line
					(at 0 -27.94 0)
					(length 3.81)
					(name "B12"
						(effects
							(font
								(size 1.27 1.27)
							)
						)
					)
					(number "B12"
						(effects
							(font
								(size 1.27 1.27)
							)
						)
					)
				)
				(pin passive line
					(at 0 -30.48 0)
					(length 3.81)
					(name "B13"
						(effects
							(font
								(size 1.27 1.27)
							)
						)
					)
					(number "B13"
						(effects
							(font
								(size 1.27 1.27)
							)
						)
					)
				)
				(pin passive line
					(at 0 -33.02 0)
					(length 3.81)
					(name "B14"
						(effects
							(font
								(size 1.27 1.27)
							)
						)
					)
					(number "B14"
						(effects
							(font
								(size 1.27 1.27)
							)
						)
					)
				)
				(pin passive line
					(at 0 -35.56 0)
					(length 3.81)
					(name "B15"
						(effects
							(font
								(size 1.27 1.27)
							)
						)
					)
					(number "B15"
						(effects
							(font
								(size 1.27 1.27)
							)
						)
					)
				)
				(pin passive line
					(at 0 -38.1 0)
					(length 3.81)
					(name "B16"
						(effects
							(font
								(size 1.27 1.27)
							)
						)
					)
					(number "B16"
						(effects
							(font
								(size 1.27 1.27)
							)
						)
					)
				)
				(pin passive line
					(at 0 -40.64 0)
					(length 3.81)
					(name "B17"
						(effects
							(font
								(size 1.27 1.27)
							)
						)
					)
					(number "B17"
						(effects
							(font
								(size 1.27 1.27)
							)
						)
					)
				)
				(pin passive line
					(at 0 -43.18 0)
					(length 3.81)
					(name "B18"
						(effects
							(font
								(size 1.27 1.27)
							)
						)
					)
					(number "B18"
						(effects
							(font
								(size 1.27 1.27)
							)
						)
					)
				)
				(pin passive line
					(at 0 -45.72 0)
					(length 3.81)
					(name "B19"
						(effects
							(font
								(size 1.27 1.27)
							)
						)
					)
					(number "B19"
						(effects
							(font
								(size 1.27 1.27)
							)
						)
					)
				)
				(pin passive line
					(at 0 -2.54 0)
					(length 3.81)
					(name "B2"
						(effects
							(font
								(size 1.27 1.27)
							)
						)
					)
					(number "B2"
						(effects
							(font
								(size 1.27 1.27)
							)
						)
					)
				)
				(pin passive line
					(at 0 -48.26 0)
					(length 3.81)
					(name "B20"
						(effects
							(font
								(size 1.27 1.27)
							)
						)
					)
					(number "B20"
						(effects
							(font
								(size 1.27 1.27)
							)
						)
					)
				)
				(pin passive line
					(at 0 -50.8 0)
					(length 3.81)
					(name "B21"
						(effects
							(font
								(size 1.27 1.27)
							)
						)
					)
					(number "B21"
						(effects
							(font
								(size 1.27 1.27)
							)
						)
					)
				)
				(pin passive line
					(at 0 -53.34 0)
					(length 3.81)
					(name "B22"
						(effects
							(font
								(size 1.27 1.27)
							)
						)
					)
					(number "B22"
						(effects
							(font
								(size 1.27 1.27)
							)
						)
					)
				)
				(pin passive line
					(at 0 -55.88 0)
					(length 3.81)
					(name "B23"
						(effects
							(font
								(size 1.27 1.27)
							)
						)
					)
					(number "B23"
						(effects
							(font
								(size 1.27 1.27)
							)
						)
					)
				)
				(pin passive line
					(at 0 -58.42 0)
					(length 3.81)
					(name "B24"
						(effects
							(font
								(size 1.27 1.27)
							)
						)
					)
					(number "B24"
						(effects
							(font
								(size 1.27 1.27)
							)
						)
					)
				)
				(pin passive line
					(at 0 -60.96 0)
					(length 3.81)
					(name "B25"
						(effects
							(font
								(size 1.27 1.27)
							)
						)
					)
					(number "B25"
						(effects
							(font
								(size 1.27 1.27)
							)
						)
					)
				)
				(pin passive line
					(at 0 -63.5 0)
					(length 3.81)
					(name "B26"
						(effects
							(font
								(size 1.27 1.27)
							)
						)
					)
					(number "B26"
						(effects
							(font
								(size 1.27 1.27)
							)
						)
					)
				)
				(pin passive line
					(at 0 -66.04 0)
					(length 3.81)
					(name "B27"
						(effects
							(font
								(size 1.27 1.27)
							)
						)
					)
					(number "B27"
						(effects
							(font
								(size 1.27 1.27)
							)
						)
					)
				)
				(pin passive line
					(at 0 -68.58 0)
					(length 3.81)
					(name "B28"
						(effects
							(font
								(size 1.27 1.27)
							)
						)
					)
					(number "B28"
						(effects
							(font
								(size 1.27 1.27)
							)
						)
					)
				)
				(pin passive line
					(at 0 -71.12 0)
					(length 3.81)
					(name "B29"
						(effects
							(font
								(size 1.27 1.27)
							)
						)
					)
					(number "B29"
						(effects
							(font
								(size 1.27 1.27)
							)
						)
					)
				)
				(pin passive line
					(at 0 -5.08 0)
					(length 3.81)
					(name "B3"
						(effects
							(font
								(size 1.27 1.27)
							)
						)
					)
					(number "B3"
						(effects
							(font
								(size 1.27 1.27)
							)
						)
					)
				)
				(pin passive line
					(at 0 -73.66 0)
					(length 3.81)
					(name "B30"
						(effects
							(font
								(size 1.27 1.27)
							)
						)
					)
					(number "B30"
						(effects
							(font
								(size 1.27 1.27)
							)
						)
					)
				)
				(pin passive line
					(at 0 -76.2 0)
					(length 3.81)
					(name "B31"
						(effects
							(font
								(size 1.27 1.27)
							)
						)
					)
					(number "B31"
						(effects
							(font
								(size 1.27 1.27)
							)
						)
					)
				)
				(pin passive line
					(at 0 -78.74 0)
					(length 3.81)
					(name "B32"
						(effects
							(font
								(size 1.27 1.27)
							)
						)
					)
					(number "B32"
						(effects
							(font
								(size 1.27 1.27)
							)
						)
					)
				)
				(pin passive line
					(at 0 -81.28 0)
					(length 3.81)
					(name "B33"
						(effects
							(font
								(size 1.27 1.27)
							)
						)
					)
					(number "B33"
						(effects
							(font
								(size 1.27 1.27)
							)
						)
					)
				)
				(pin passive line
					(at 0 -83.82 0)
					(length 3.81)
					(name "B34"
						(effects
							(font
								(size 1.27 1.27)
							)
						)
					)
					(number "B34"
						(effects
							(font
								(size 1.27 1.27)
							)
						)
					)
				)
				(pin passive line
					(at 0 -86.36 0)
					(length 3.81)
					(name "B35"
						(effects
							(font
								(size 1.27 1.27)
							)
						)
					)
					(number "B35"
						(effects
							(font
								(size 1.27 1.27)
							)
						)
					)
				)
				(pin passive line
					(at 0 -88.9 0)
					(length 3.81)
					(name "B36"
						(effects
							(font
								(size 1.27 1.27)
							)
						)
					)
					(number "B36"
						(effects
							(font
								(size 1.27 1.27)
							)
						)
					)
				)
				(pin passive line
					(at 0 -91.44 0)
					(length 3.81)
					(name "B37"
						(effects
							(font
								(size 1.27 1.27)
							)
						)
					)
					(number "B37"
						(effects
							(font
								(size 1.27 1.27)
							)
						)
					)
				)
				(pin passive line
					(at 0 -93.98 0)
					(length 3.81)
					(name "B38"
						(effects
							(font
								(size 1.27 1.27)
							)
						)
					)
					(number "B38"
						(effects
							(font
								(size 1.27 1.27)
							)
						)
					)
				)
				(pin passive line
					(at 0 -96.52 0)
					(length 3.81)
					(name "B39"
						(effects
							(font
								(size 1.27 1.27)
							)
						)
					)
					(number "B39"
						(effects
							(font
								(size 1.27 1.27)
							)
						)
					)
				)
				(pin passive line
					(at 0 -7.62 0)
					(length 3.81)
					(name "B4"
						(effects
							(font
								(size 1.27 1.27)
							)
						)
					)
					(number "B4"
						(effects
							(font
								(size 1.27 1.27)
							)
						)
					)
				)
				(pin passive line
					(at 0 -99.06 0)
					(length 3.81)
					(name "B40"
						(effects
							(font
								(size 1.27 1.27)
							)
						)
					)
					(number "B40"
						(effects
							(font
								(size 1.27 1.27)
							)
						)
					)
				)
				(pin passive line
					(at 0 -101.6 0)
					(length 3.81)
					(name "B41"
						(effects
							(font
								(size 1.27 1.27)
							)
						)
					)
					(number "B41"
						(effects
							(font
								(size 1.27 1.27)
							)
						)
					)
				)
				(pin passive line
					(at 0 -10.16 0)
					(length 3.81)
					(name "B5"
						(effects
							(font
								(size 1.27 1.27)
							)
						)
					)
					(number "B5"
						(effects
							(font
								(size 1.27 1.27)
							)
						)
					)
				)
				(pin passive line
					(at 0 -12.7 0)
					(length 3.81)
					(name "B6"
						(effects
							(font
								(size 1.27 1.27)
							)
						)
					)
					(number "B6"
						(effects
							(font
								(size 1.27 1.27)
							)
						)
					)
				)
				(pin passive line
					(at 0 -15.24 0)
					(length 3.81)
					(name "B7"
						(effects
							(font
								(size 1.27 1.27)
							)
						)
					)
					(number "B7"
						(effects
							(font
								(size 1.27 1.27)
							)
						)
					)
				)
				(pin passive line
					(at 0 -17.78 0)
					(length 3.81)
					(name "B8"
						(effects
							(font
								(size 1.27 1.27)
							)
						)
					)
					(number "B8"
						(effects
							(font
								(size 1.27 1.27)
							)
						)
					)
				)
				(pin passive line
					(at 0 -20.32 0)
					(length 3.81)
					(name "B9"
						(effects
							(font
								(size 1.27 1.27)
							)
						)
					)
					(number "B9"
						(effects
							(font
								(size 1.27 1.27)
							)
						)
					)
				)
			)
			(symbol "PCIe_x16_10146070-113Y0LF-vertical_2_1"
				(rectangle
					(start 3.81 -104.14)
					(end 19.05 2.54)
					(stroke
						(width 0.254)
						(type default)
					)
					(fill
						(type background)
					)
				)
				(pin passive line
					(at 22.86 0 180)
					(length 3.81)
					(name "A42"
						(effects
							(font
								(size 1.27 1.27)
							)
						)
					)
					(number "A42"
						(effects
							(font
								(size 1.27 1.27)
							)
						)
					)
				)
				(pin passive line
					(at 22.86 -2.54 180)
					(length 3.81)
					(name "A43"
						(effects
							(font
								(size 1.27 1.27)
							)
						)
					)
					(number "A43"
						(effects
							(font
								(size 1.27 1.27)
							)
						)
					)
				)
				(pin passive line
					(at 22.86 -5.08 180)
					(length 3.81)
					(name "A44"
						(effects
							(font
								(size 1.27 1.27)
							)
						)
					)
					(number "A44"
						(effects
							(font
								(size 1.27 1.27)
							)
						)
					)
				)
				(pin passive line
					(at 22.86 -7.62 180)
					(length 3.81)
					(name "A45"
						(effects
							(font
								(size 1.27 1.27)
							)
						)
					)
					(number "A45"
						(effects
							(font
								(size 1.27 1.27)
							)
						)
					)
				)
				(pin passive line
					(at 22.86 -10.16 180)
					(length 3.81)
					(name "A46"
						(effects
							(font
								(size 1.27 1.27)
							)
						)
					)
					(number "A46"
						(effects
							(font
								(size 1.27 1.27)
							)
						)
					)
				)
				(pin passive line
					(at 22.86 -12.7 180)
					(length 3.81)
					(name "A47"
						(effects
							(font
								(size 1.27 1.27)
							)
						)
					)
					(number "A47"
						(effects
							(font
								(size 1.27 1.27)
							)
						)
					)
				)
				(pin passive line
					(at 22.86 -15.24 180)
					(length 3.81)
					(name "A48"
						(effects
							(font
								(size 1.27 1.27)
							)
						)
					)
					(number "A48"
						(effects
							(font
								(size 1.27 1.27)
							)
						)
					)
				)
				(pin passive line
					(at 22.86 -17.78 180)
					(length 3.81)
					(name "A49"
						(effects
							(font
								(size 1.27 1.27)
							)
						)
					)
					(number "A49"
						(effects
							(font
								(size 1.27 1.27)
							)
						)
					)
				)
				(pin passive line
					(at 22.86 -20.32 180)
					(length 3.81)
					(name "A50"
						(effects
							(font
								(size 1.27 1.27)
							)
						)
					)
					(number "A50"
						(effects
							(font
								(size 1.27 1.27)
							)
						)
					)
				)
				(pin passive line
					(at 22.86 -22.86 180)
					(length 3.81)
					(name "A51"
						(effects
							(font
								(size 1.27 1.27)
							)
						)
					)
					(number "A51"
						(effects
							(font
								(size 1.27 1.27)
							)
						)
					)
				)
				(pin passive line
					(at 22.86 -25.4 180)
					(length 3.81)
					(name "A52"
						(effects
							(font
								(size 1.27 1.27)
							)
						)
					)
					(number "A52"
						(effects
							(font
								(size 1.27 1.27)
							)
						)
					)
				)
				(pin passive line
					(at 22.86 -27.94 180)
					(length 3.81)
					(name "A53"
						(effects
							(font
								(size 1.27 1.27)
							)
						)
					)
					(number "A53"
						(effects
							(font
								(size 1.27 1.27)
							)
						)
					)
				)
				(pin passive line
					(at 22.86 -30.48 180)
					(length 3.81)
					(name "A54"
						(effects
							(font
								(size 1.27 1.27)
							)
						)
					)
					(number "A54"
						(effects
							(font
								(size 1.27 1.27)
							)
						)
					)
				)
				(pin passive line
					(at 22.86 -33.02 180)
					(length 3.81)
					(name "A55"
						(effects
							(font
								(size 1.27 1.27)
							)
						)
					)
					(number "A55"
						(effects
							(font
								(size 1.27 1.27)
							)
						)
					)
				)
				(pin passive line
					(at 22.86 -35.56 180)
					(length 3.81)
					(name "A56"
						(effects
							(font
								(size 1.27 1.27)
							)
						)
					)
					(number "A56"
						(effects
							(font
								(size 1.27 1.27)
							)
						)
					)
				)
				(pin passive line
					(at 22.86 -38.1 180)
					(length 3.81)
					(name "A57"
						(effects
							(font
								(size 1.27 1.27)
							)
						)
					)
					(number "A57"
						(effects
							(font
								(size 1.27 1.27)
							)
						)
					)
				)
				(pin passive line
					(at 22.86 -40.64 180)
					(length 3.81)
					(name "A58"
						(effects
							(font
								(size 1.27 1.27)
							)
						)
					)
					(number "A58"
						(effects
							(font
								(size 1.27 1.27)
							)
						)
					)
				)
				(pin passive line
					(at 22.86 -43.18 180)
					(length 3.81)
					(name "A59"
						(effects
							(font
								(size 1.27 1.27)
							)
						)
					)
					(number "A59"
						(effects
							(font
								(size 1.27 1.27)
							)
						)
					)
				)
				(pin passive line
					(at 22.86 -45.72 180)
					(length 3.81)
					(name "A60"
						(effects
							(font
								(size 1.27 1.27)
							)
						)
					)
					(number "A60"
						(effects
							(font
								(size 1.27 1.27)
							)
						)
					)
				)
				(pin passive line
					(at 22.86 -48.26 180)
					(length 3.81)
					(name "A61"
						(effects
							(font
								(size 1.27 1.27)
							)
						)
					)
					(number "A61"
						(effects
							(font
								(size 1.27 1.27)
							)
						)
					)
				)
				(pin passive line
					(at 22.86 -50.8 180)
					(length 3.81)
					(name "A62"
						(effects
							(font
								(size 1.27 1.27)
							)
						)
					)
					(number "A62"
						(effects
							(font
								(size 1.27 1.27)
							)
						)
					)
				)
				(pin passive line
					(at 22.86 -53.34 180)
					(length 3.81)
					(name "A63"
						(effects
							(font
								(size 1.27 1.27)
							)
						)
					)
					(number "A63"
						(effects
							(font
								(size 1.27 1.27)
							)
						)
					)
				)
				(pin passive line
					(at 22.86 -55.88 180)
					(length 3.81)
					(name "A64"
						(effects
							(font
								(size 1.27 1.27)
							)
						)
					)
					(number "A64"
						(effects
							(font
								(size 1.27 1.27)
							)
						)
					)
				)
				(pin passive line
					(at 22.86 -58.42 180)
					(length 3.81)
					(name "A65"
						(effects
							(font
								(size 1.27 1.27)
							)
						)
					)
					(number "A65"
						(effects
							(font
								(size 1.27 1.27)
							)
						)
					)
				)
				(pin passive line
					(at 22.86 -60.96 180)
					(length 3.81)
					(name "A66"
						(effects
							(font
								(size 1.27 1.27)
							)
						)
					)
					(number "A66"
						(effects
							(font
								(size 1.27 1.27)
							)
						)
					)
				)
				(pin passive line
					(at 22.86 -63.5 180)
					(length 3.81)
					(name "A67"
						(effects
							(font
								(size 1.27 1.27)
							)
						)
					)
					(number "A67"
						(effects
							(font
								(size 1.27 1.27)
							)
						)
					)
				)
				(pin passive line
					(at 22.86 -66.04 180)
					(length 3.81)
					(name "A68"
						(effects
							(font
								(size 1.27 1.27)
							)
						)
					)
					(number "A68"
						(effects
							(font
								(size 1.27 1.27)
							)
						)
					)
				)
				(pin passive line
					(at 22.86 -68.58 180)
					(length 3.81)
					(name "A69"
						(effects
							(font
								(size 1.27 1.27)
							)
						)
					)
					(number "A69"
						(effects
							(font
								(size 1.27 1.27)
							)
						)
					)
				)
				(pin passive line
					(at 22.86 -71.12 180)
					(length 3.81)
					(name "A70"
						(effects
							(font
								(size 1.27 1.27)
							)
						)
					)
					(number "A70"
						(effects
							(font
								(size 1.27 1.27)
							)
						)
					)
				)
				(pin passive line
					(at 22.86 -73.66 180)
					(length 3.81)
					(name "A71"
						(effects
							(font
								(size 1.27 1.27)
							)
						)
					)
					(number "A71"
						(effects
							(font
								(size 1.27 1.27)
							)
						)
					)
				)
				(pin passive line
					(at 22.86 -76.2 180)
					(length 3.81)
					(name "A72"
						(effects
							(font
								(size 1.27 1.27)
							)
						)
					)
					(number "A72"
						(effects
							(font
								(size 1.27 1.27)
							)
						)
					)
				)
				(pin passive line
					(at 22.86 -78.74 180)
					(length 3.81)
					(name "A73"
						(effects
							(font
								(size 1.27 1.27)
							)
						)
					)
					(number "A73"
						(effects
							(font
								(size 1.27 1.27)
							)
						)
					)
				)
				(pin passive line
					(at 22.86 -81.28 180)
					(length 3.81)
					(name "A74"
						(effects
							(font
								(size 1.27 1.27)
							)
						)
					)
					(number "A74"
						(effects
							(font
								(size 1.27 1.27)
							)
						)
					)
				)
				(pin passive line
					(at 22.86 -83.82 180)
					(length 3.81)
					(name "A75"
						(effects
							(font
								(size 1.27 1.27)
							)
						)
					)
					(number "A75"
						(effects
							(font
								(size 1.27 1.27)
							)
						)
					)
				)
				(pin passive line
					(at 22.86 -86.36 180)
					(length 3.81)
					(name "A76"
						(effects
							(font
								(size 1.27 1.27)
							)
						)
					)
					(number "A76"
						(effects
							(font
								(size 1.27 1.27)
							)
						)
					)
				)
				(pin passive line
					(at 22.86 -88.9 180)
					(length 3.81)
					(name "A77"
						(effects
							(font
								(size 1.27 1.27)
							)
						)
					)
					(number "A77"
						(effects
							(font
								(size 1.27 1.27)
							)
						)
					)
				)
				(pin passive line
					(at 22.86 -91.44 180)
					(length 3.81)
					(name "A78"
						(effects
							(font
								(size 1.27 1.27)
							)
						)
					)
					(number "A78"
						(effects
							(font
								(size 1.27 1.27)
							)
						)
					)
				)
				(pin passive line
					(at 22.86 -93.98 180)
					(length 3.81)
					(name "A79"
						(effects
							(font
								(size 1.27 1.27)
							)
						)
					)
					(number "A79"
						(effects
							(font
								(size 1.27 1.27)
							)
						)
					)
				)
				(pin passive line
					(at 22.86 -96.52 180)
					(length 3.81)
					(name "A80"
						(effects
							(font
								(size 1.27 1.27)
							)
						)
					)
					(number "A80"
						(effects
							(font
								(size 1.27 1.27)
							)
						)
					)
				)
				(pin passive line
					(at 22.86 -99.06 180)
					(length 3.81)
					(name "A81"
						(effects
							(font
								(size 1.27 1.27)
							)
						)
					)
					(number "A81"
						(effects
							(font
								(size 1.27 1.27)
							)
						)
					)
				)
				(pin passive line
					(at 22.86 -101.6 180)
					(length 3.81)
					(name "A82"
						(effects
							(font
								(size 1.27 1.27)
							)
						)
					)
					(number "A82"
						(effects
							(font
								(size 1.27 1.27)
							)
						)
					)
				)
				(pin passive line
					(at 0 0 0)
					(length 3.81)
					(name "B42"
						(effects
							(font
								(size 1.27 1.27)
							)
						)
					)
					(number "B42"
						(effects
							(font
								(size 1.27 1.27)
							)
						)
					)
				)
				(pin passive line
					(at 0 -2.54 0)
					(length 3.81)
					(name "B43"
						(effects
							(font
								(size 1.27 1.27)
							)
						)
					)
					(number "B43"
						(effects
							(font
								(size 1.27 1.27)
							)
						)
					)
				)
				(pin passive line
					(at 0 -5.08 0)
					(length 3.81)
					(name "B44"
						(effects
							(font
								(size 1.27 1.27)
							)
						)
					)
					(number "B44"
						(effects
							(font
								(size 1.27 1.27)
							)
						)
					)
				)
				(pin passive line
					(at 0 -7.62 0)
					(length 3.81)
					(name "B45"
						(effects
							(font
								(size 1.27 1.27)
							)
						)
					)
					(number "B45"
						(effects
							(font
								(size 1.27 1.27)
							)
						)
					)
				)
				(pin passive line
					(at 0 -10.16 0)
					(length 3.81)
					(name "B46"
						(effects
							(font
								(size 1.27 1.27)
							)
						)
					)
					(number "B46"
						(effects
							(font
								(size 1.27 1.27)
							)
						)
					)
				)
				(pin passive line
					(at 0 -12.7 0)
					(length 3.81)
					(name "B47"
						(effects
							(font
								(size 1.27 1.27)
							)
						)
					)
					(number "B47"
						(effects
							(font
								(size 1.27 1.27)
							)
						)
					)
				)
				(pin passive line
					(at 0 -15.24 0)
					(length 3.81)
					(name "B48"
						(effects
							(font
								(size 1.27 1.27)
							)
						)
					)
					(number "B48"
						(effects
							(font
								(size 1.27 1.27)
							)
						)
					)
				)
				(pin passive line
					(at 0 -17.78 0)
					(length 3.81)
					(name "B49"
						(effects
							(font
								(size 1.27 1.27)
							)
						)
					)
					(number "B49"
						(effects
							(font
								(size 1.27 1.27)
							)
						)
					)
				)
				(pin passive line
					(at 0 -20.32 0)
					(length 3.81)
					(name "B50"
						(effects
							(font
								(size 1.27 1.27)
							)
						)
					)
					(number "B50"
						(effects
							(font
								(size 1.27 1.27)
							)
						)
					)
				)
				(pin passive line
					(at 0 -22.86 0)
					(length 3.81)
					(name "B51"
						(effects
							(font
								(size 1.27 1.27)
							)
						)
					)
					(number "B51"
						(effects
							(font
								(size 1.27 1.27)
							)
						)
					)
				)
				(pin passive line
					(at 0 -25.4 0)
					(length 3.81)
					(name "B52"
						(effects
							(font
								(size 1.27 1.27)
							)
						)
					)
					(number "B52"
						(effects
							(font
								(size 1.27 1.27)
							)
						)
					)
				)
				(pin passive line
					(at 0 -27.94 0)
					(length 3.81)
					(name "B53"
						(effects
							(font
								(size 1.27 1.27)
							)
						)
					)
					(number "B53"
						(effects
							(font
								(size 1.27 1.27)
							)
						)
					)
				)
				(pin passive line
					(at 0 -30.48 0)
					(length 3.81)
					(name "B54"
						(effects
							(font
								(size 1.27 1.27)
							)
						)
					)
					(number "B54"
						(effects
							(font
								(size 1.27 1.27)
							)
						)
					)
				)
				(pin passive line
					(at 0 -33.02 0)
					(length 3.81)
					(name "B55"
						(effects
							(font
								(size 1.27 1.27)
							)
						)
					)
					(number "B55"
						(effects
							(font
								(size 1.27 1.27)
							)
						)
					)
				)
				(pin passive line
					(at 0 -35.56 0)
					(length 3.81)
					(name "B56"
						(effects
							(font
								(size 1.27 1.27)
							)
						)
					)
					(number "B56"
						(effects
							(font
								(size 1.27 1.27)
							)
						)
					)
				)
				(pin passive line
					(at 0 -38.1 0)
					(length 3.81)
					(name "B57"
						(effects
							(font
								(size 1.27 1.27)
							)
						)
					)
					(number "B57"
						(effects
							(font
								(size 1.27 1.27)
							)
						)
					)
				)
				(pin passive line
					(at 0 -40.64 0)
					(length 3.81)
					(name "B58"
						(effects
							(font
								(size 1.27 1.27)
							)
						)
					)
					(number "B58"
						(effects
							(font
								(size 1.27 1.27)
							)
						)
					)
				)
				(pin passive line
					(at 0 -43.18 0)
					(length 3.81)
					(name "B59"
						(effects
							(font
								(size 1.27 1.27)
							)
						)
					)
					(number "B59"
						(effects
							(font
								(size 1.27 1.27)
							)
						)
					)
				)
				(pin passive line
					(at 0 -45.72 0)
					(length 3.81)
					(name "B60"
						(effects
							(font
								(size 1.27 1.27)
							)
						)
					)
					(number "B60"
						(effects
							(font
								(size 1.27 1.27)
							)
						)
					)
				)
				(pin passive line
					(at 0 -48.26 0)
					(length 3.81)
					(name "B61"
						(effects
							(font
								(size 1.27 1.27)
							)
						)
					)
					(number "B61"
						(effects
							(font
								(size 1.27 1.27)
							)
						)
					)
				)
				(pin passive line
					(at 0 -50.8 0)
					(length 3.81)
					(name "B62"
						(effects
							(font
								(size 1.27 1.27)
							)
						)
					)
					(number "B62"
						(effects
							(font
								(size 1.27 1.27)
							)
						)
					)
				)
				(pin passive line
					(at 0 -53.34 0)
					(length 3.81)
					(name "B63"
						(effects
							(font
								(size 1.27 1.27)
							)
						)
					)
					(number "B63"
						(effects
							(font
								(size 1.27 1.27)
							)
						)
					)
				)
				(pin passive line
					(at 0 -55.88 0)
					(length 3.81)
					(name "B64"
						(effects
							(font
								(size 1.27 1.27)
							)
						)
					)
					(number "B64"
						(effects
							(font
								(size 1.27 1.27)
							)
						)
					)
				)
				(pin passive line
					(at 0 -58.42 0)
					(length 3.81)
					(name "B65"
						(effects
							(font
								(size 1.27 1.27)
							)
						)
					)
					(number "B65"
						(effects
							(font
								(size 1.27 1.27)
							)
						)
					)
				)
				(pin passive line
					(at 0 -60.96 0)
					(length 3.81)
					(name "B66"
						(effects
							(font
								(size 1.27 1.27)
							)
						)
					)
					(number "B66"
						(effects
							(font
								(size 1.27 1.27)
							)
						)
					)
				)
				(pin passive line
					(at 0 -63.5 0)
					(length 3.81)
					(name "B67"
						(effects
							(font
								(size 1.27 1.27)
							)
						)
					)
					(number "B67"
						(effects
							(font
								(size 1.27 1.27)
							)
						)
					)
				)
				(pin passive line
					(at 0 -66.04 0)
					(length 3.81)
					(name "B68"
						(effects
							(font
								(size 1.27 1.27)
							)
						)
					)
					(number "B68"
						(effects
							(font
								(size 1.27 1.27)
							)
						)
					)
				)
				(pin passive line
					(at 0 -68.58 0)
					(length 3.81)
					(name "B69"
						(effects
							(font
								(size 1.27 1.27)
							)
						)
					)
					(number "B69"
						(effects
							(font
								(size 1.27 1.27)
							)
						)
					)
				)
				(pin passive line
					(at 0 -71.12 0)
					(length 3.81)
					(name "B70"
						(effects
							(font
								(size 1.27 1.27)
							)
						)
					)
					(number "B70"
						(effects
							(font
								(size 1.27 1.27)
							)
						)
					)
				)
				(pin passive line
					(at 0 -73.66 0)
					(length 3.81)
					(name "B71"
						(effects
							(font
								(size 1.27 1.27)
							)
						)
					)
					(number "B71"
						(effects
							(font
								(size 1.27 1.27)
							)
						)
					)
				)
				(pin passive line
					(at 0 -76.2 0)
					(length 3.81)
					(name "B72"
						(effects
							(font
								(size 1.27 1.27)
							)
						)
					)
					(number "B72"
						(effects
							(font
								(size 1.27 1.27)
							)
						)
					)
				)
				(pin passive line
					(at 0 -78.74 0)
					(length 3.81)
					(name "B73"
						(effects
							(font
								(size 1.27 1.27)
							)
						)
					)
					(number "B73"
						(effects
							(font
								(size 1.27 1.27)
							)
						)
					)
				)
				(pin passive line
					(at 0 -81.28 0)
					(length 3.81)
					(name "B74"
						(effects
							(font
								(size 1.27 1.27)
							)
						)
					)
					(number "B74"
						(effects
							(font
								(size 1.27 1.27)
							)
						)
					)
				)
				(pin passive line
					(at 0 -83.82 0)
					(length 3.81)
					(name "B75"
						(effects
							(font
								(size 1.27 1.27)
							)
						)
					)
					(number "B75"
						(effects
							(font
								(size 1.27 1.27)
							)
						)
					)
				)
				(pin passive line
					(at 0 -86.36 0)
					(length 3.81)
					(name "B76"
						(effects
							(font
								(size 1.27 1.27)
							)
						)
					)
					(number "B76"
						(effects
							(font
								(size 1.27 1.27)
							)
						)
					)
				)
				(pin passive line
					(at 0 -88.9 0)
					(length 3.81)
					(name "B77"
						(effects
							(font
								(size 1.27 1.27)
							)
						)
					)
					(number "B77"
						(effects
							(font
								(size 1.27 1.27)
							)
						)
					)
				)
				(pin passive line
					(at 0 -91.44 0)
					(length 3.81)
					(name "B78"
						(effects
							(font
								(size 1.27 1.27)
							)
						)
					)
					(number "B78"
						(effects
							(font
								(size 1.27 1.27)
							)
						)
					)
				)
				(pin passive line
					(at 0 -93.98 0)
					(length 3.81)
					(name "B79"
						(effects
							(font
								(size 1.27 1.27)
							)
						)
					)
					(number "B79"
						(effects
							(font
								(size 1.27 1.27)
							)
						)
					)
				)
				(pin passive line
					(at 0 -96.52 0)
					(length 3.81)
					(name "B80"
						(effects
							(font
								(size 1.27 1.27)
							)
						)
					)
					(number "B80"
						(effects
							(font
								(size 1.27 1.27)
							)
						)
					)
				)
				(pin passive line
					(at 0 -99.06 0)
					(length 3.81)
					(name "B81"
						(effects
							(font
								(size 1.27 1.27)
							)
						)
					)
					(number "B81"
						(effects
							(font
								(size 1.27 1.27)
							)
						)
					)
				)
				(pin passive line
					(at 0 -101.6 0)
					(length 3.81)
					(name "B82"
						(effects
							(font
								(size 1.27 1.27)
							)
						)
					)
					(number "B82"
						(effects
							(font
								(size 1.27 1.27)
							)
						)
					)
				)
			)
		)
	(symbol "antmicroResistors0402:R_0R_0402"
			(pin_numbers hide)
			(pin_names hide)
			(exclude_from_sim no)
			(in_bom yes)
			(on_board yes)
			(property "Reference" "R"
				(at 20.32 -5.08 0)
				(effects
					(font
						(size 1.27 1.27)
						(thickness 0.15)
					)
					(justify left bottom)
				)
			)
			(property "Value" "R_0R_0402"
				(at 20.32 -12.7 0)
				(effects
					(font
						(size 1.27 1.27)
						(thickness 0.15)
					)
					(justify left bottom)
					(hide yes)
				)
			)
			(property "Footprint" "antmicro-footprints:R_0402_1005Metric"
				(at 20.32 -15.24 0)
				(effects
					(font
						(size 1.27 1.27)
						(thickness 0.15)
					)
					(justify left bottom)
					(hide yes)
				)
			)
			(property "Datasheet" "https://industrial.panasonic.com/cdbs/www-data/pdf/RDA0000/AOA0000C301.pdf"
				(at 20.32 -17.78 0)
				(effects
					(font
						(size 1.27 1.27)
						(thickness 0.15)
					)
					(justify left bottom)
					(hide yes)
				)
			)
			(property "Description" "SMD Chip Resistor, Jumper, 0 ohm, 100 mW, 0402 [1005 Metric], Thick Film, General Purpose"
				(at 0 0 0)
				(effects
					(font
						(size 1.27 1.27)
					)
					(hide yes)
				)
			)
			(property "MPN" "ERJ2GE0R00X"
				(at 20.32 -20.32 0)
				(effects
					(font
						(size 1.27 1.27)
						(thickness 0.15)
					)
					(justify left bottom)
					(hide yes)
				)
			)
			(property "Manufacturer" "Panasonic"
				(at 20.32 -22.86 0)
				(effects
					(font
						(size 1.27 1.27)
						(thickness 0.15)
					)
					(justify left bottom)
					(hide yes)
				)
			)
			(property "License" "Apache-2.0"
				(at 20.32 -25.4 0)
				(effects
					(font
						(size 1.27 1.27)
						(thickness 0.15)
					)
					(justify left bottom)
					(hide yes)
				)
			)
			(property "Author" "Antmicro"
				(at 20.32 -27.94 0)
				(effects
					(font
						(size 1.27 1.27)
						(thickness 0.15)
					)
					(justify left bottom)
					(hide yes)
				)
			)
			(property "Val" "0R"
				(at 20.32 -7.62 0)
				(effects
					(font
						(size 1.27 1.27)
						(thickness 0.15)
					)
					(justify left bottom)
				)
			)
			(property "Tolerance" "~"
				(at 20.32 -10.16 0)
				(effects
					(font
						(size 1.27 1.27)
					)
					(justify left bottom)
					(hide yes)
				)
			)
			(property "Current" "1A"
				(at 20.32 -30.48 0)
				(effects
					(font
						(size 1.27 1.27)
						(thickness 0.15)
					)
					(justify left bottom)
					(hide yes)
				)
			)
			(property "ki_keywords" "0402, SMT, RESISTOR, PASSIVE"
				(at 0 0 0)
				(effects
					(font
						(size 1.27 1.27)
					)
					(hide yes)
				)
			)
			(symbol "R_0R_0402_0_1"
				(rectangle
					(start 0.635 0.889)
					(end 4.445 -0.889)
					(stroke
						(width 0.254)
						(type default)
					)
					(fill
						(type none)
					)
				)
			)
			(symbol "R_0R_0402_1_1"
				(pin passive line
					(at 0 0 0)
					(length 0.635)
					(name "~"
						(effects
							(font
								(size 1.27 1.27)
							)
						)
					)
					(number "1"
						(effects
							(font
								(size 1.27 1.27)
							)
						)
					)
				)
				(pin passive line
					(at 5.08 0 180)
					(length 0.635)
					(name "~"
						(effects
							(font
								(size 1.27 1.27)
							)
						)
					)
					(number "2"
						(effects
							(font
								(size 1.27 1.27)
							)
						)
					)
				)
			)
		)
	(symbol "antmicroResistors0402:R_100R_0402"
			(pin_numbers hide)
			(pin_names hide)
			(exclude_from_sim no)
			(in_bom yes)
			(on_board yes)
			(property "Reference" "R"
				(at 20.32 -5.08 0)
				(effects
					(font
						(size 1.27 1.27)
						(thickness 0.15)
					)
					(justify left bottom)
				)
			)
			(property "Value" "R_100R_0402"
				(at 20.32 -12.7 0)
				(effects
					(font
						(size 1.27 1.27)
						(thickness 0.15)
					)
					(justify left bottom)
					(hide yes)
				)
			)
			(property "Footprint" "antmicro-footprints:R_0402_1005Metric"
				(at 20.32 -15.24 0)
				(effects
					(font
						(size 1.27 1.27)
						(thickness 0.15)
					)
					(justify left bottom)
					(hide yes)
				)
			)
			(property "Datasheet" "https://www.bourns.com/docs/product-datasheets/cr.pdf"
				(at 20.32 -17.78 0)
				(effects
					(font
						(size 1.27 1.27)
						(thickness 0.15)
					)
					(justify left bottom)
					(hide yes)
				)
			)
			(property "Description" "SMD Chip Resistor, 100 ohm, ± 1%, 62.5 mW, 0402 [1005 Metric], Thick Film, General Purpose"
				(at 0 0 0)
				(effects
					(font
						(size 1.27 1.27)
					)
					(hide yes)
				)
			)
			(property "MPN" "CR0402-FX-1000GLF"
				(at 20.32 -20.32 0)
				(effects
					(font
						(size 1.27 1.27)
						(thickness 0.15)
					)
					(justify left bottom)
					(hide yes)
				)
			)
			(property "Manufacturer" "Bourns"
				(at 20.32 -22.86 0)
				(effects
					(font
						(size 1.27 1.27)
						(thickness 0.15)
					)
					(justify left bottom)
					(hide yes)
				)
			)
			(property "License" "Apache-2.0"
				(at 20.32 -25.4 0)
				(effects
					(font
						(size 1.27 1.27)
						(thickness 0.15)
					)
					(justify left bottom)
					(hide yes)
				)
			)
			(property "Author" "Antmicro"
				(at 20.32 -27.94 0)
				(effects
					(font
						(size 1.27 1.27)
						(thickness 0.15)
					)
					(justify left bottom)
					(hide yes)
				)
			)
			(property "Val" "100R"
				(at 20.32 -7.62 0)
				(effects
					(font
						(size 1.27 1.27)
						(thickness 0.15)
					)
					(justify left bottom)
				)
			)
			(property "Tolerance" "1%"
				(at 20.32 -10.16 0)
				(effects
					(font
						(size 1.27 1.27)
					)
					(justify left bottom)
					(hide yes)
				)
			)
			(property "ki_keywords" "0402, SMT, RESISTOR, PASSIVE"
				(at 0 0 0)
				(effects
					(font
						(size 1.27 1.27)
					)
					(hide yes)
				)
			)
			(symbol "R_100R_0402_0_1"
				(rectangle
					(start 0.635 0.889)
					(end 4.445 -0.889)
					(stroke
						(width 0.254)
						(type default)
					)
					(fill
						(type none)
					)
				)
			)
			(symbol "R_100R_0402_1_1"
				(pin passive line
					(at 0 0 0)
					(length 0.635)
					(name "~"
						(effects
							(font
								(size 1.27 1.27)
							)
						)
					)
					(number "1"
						(effects
							(font
								(size 1.27 1.27)
							)
						)
					)
				)
				(pin passive line
					(at 5.08 0 180)
					(length 0.635)
					(name "~"
						(effects
							(font
								(size 1.27 1.27)
							)
						)
					)
					(number "2"
						(effects
							(font
								(size 1.27 1.27)
							)
						)
					)
				)
			)
		)
	(symbol "antmicroResistors0402:R_100k_0402"
			(pin_numbers hide)
			(pin_names hide)
			(exclude_from_sim no)
			(in_bom yes)
			(on_board yes)
			(property "Reference" "R"
				(at 20.32 -5.08 0)
				(effects
					(font
						(size 1.27 1.27)
						(thickness 0.15)
					)
					(justify left bottom)
				)
			)
			(property "Value" "R_100k_0402"
				(at 20.32 -12.7 0)
				(effects
					(font
						(size 1.27 1.27)
						(thickness 0.15)
					)
					(justify left bottom)
					(hide yes)
				)
			)
			(property "Footprint" "antmicro-footprints:R_0402_1005Metric"
				(at 20.32 -15.24 0)
				(effects
					(font
						(size 1.27 1.27)
						(thickness 0.15)
					)
					(justify left bottom)
					(hide yes)
				)
			)
			(property "Datasheet" "https://www.bourns.com/docs/product-datasheets/cr.pdf"
				(at 20.32 -17.78 0)
				(effects
					(font
						(size 1.27 1.27)
						(thickness 0.15)
					)
					(justify left bottom)
					(hide yes)
				)
			)
			(property "Description" "SMD Chip Resistor, 100 kohm, ± 1%, 62.5 mW, 0402 [1005 Metric], Thick Film, General Purpose"
				(at 0 0 0)
				(effects
					(font
						(size 1.27 1.27)
					)
					(hide yes)
				)
			)
			(property "MPN" "CR0402-FX-1003GLF"
				(at 20.32 -20.32 0)
				(effects
					(font
						(size 1.27 1.27)
						(thickness 0.15)
					)
					(justify left bottom)
					(hide yes)
				)
			)
			(property "Manufacturer" "Bourns"
				(at 20.32 -22.86 0)
				(effects
					(font
						(size 1.27 1.27)
						(thickness 0.15)
					)
					(justify left bottom)
					(hide yes)
				)
			)
			(property "License" "Apache-2.0"
				(at 20.32 -25.4 0)
				(effects
					(font
						(size 1.27 1.27)
						(thickness 0.15)
					)
					(justify left bottom)
					(hide yes)
				)
			)
			(property "Author" "Antmicro"
				(at 20.32 -27.94 0)
				(effects
					(font
						(size 1.27 1.27)
						(thickness 0.15)
					)
					(justify left bottom)
					(hide yes)
				)
			)
			(property "Val" "100k"
				(at 20.32 -7.62 0)
				(effects
					(font
						(size 1.27 1.27)
						(thickness 0.15)
					)
					(justify left bottom)
				)
			)
			(property "Tolerance" "1%"
				(at 20.32 -10.16 0)
				(effects
					(font
						(size 1.27 1.27)
					)
					(justify left bottom)
					(hide yes)
				)
			)
			(property "ki_keywords" "0402, SMT, RESISTOR, PASSIVE"
				(at 0 0 0)
				(effects
					(font
						(size 1.27 1.27)
					)
					(hide yes)
				)
			)
			(symbol "R_100k_0402_0_1"
				(rectangle
					(start 0.635 0.889)
					(end 4.445 -0.889)
					(stroke
						(width 0.254)
						(type default)
					)
					(fill
						(type none)
					)
				)
			)
			(symbol "R_100k_0402_1_1"
				(pin passive line
					(at 0 0 0)
					(length 0.635)
					(name "~"
						(effects
							(font
								(size 1.27 1.27)
							)
						)
					)
					(number "1"
						(effects
							(font
								(size 1.27 1.27)
							)
						)
					)
				)
				(pin passive line
					(at 5.08 0 180)
					(length 0.635)
					(name "~"
						(effects
							(font
								(size 1.27 1.27)
							)
						)
					)
					(number "2"
						(effects
							(font
								(size 1.27 1.27)
							)
						)
					)
				)
			)
		)
	(symbol "antmicroResistors0402:R_10k_0402"
			(pin_numbers hide)
			(pin_names hide)
			(exclude_from_sim no)
			(in_bom yes)
			(on_board yes)
			(property "Reference" "R"
				(at 20.32 -5.08 0)
				(effects
					(font
						(size 1.27 1.27)
						(thickness 0.15)
					)
					(justify left bottom)
				)
			)
			(property "Value" "R_10k_0402"
				(at 20.32 -12.7 0)
				(effects
					(font
						(size 1.27 1.27)
						(thickness 0.15)
					)
					(justify left bottom)
					(hide yes)
				)
			)
			(property "Footprint" "antmicro-footprints:R_0402_1005Metric"
				(at 20.32 -15.24 0)
				(effects
					(font
						(size 1.27 1.27)
						(thickness 0.15)
					)
					(justify left bottom)
					(hide yes)
				)
			)
			(property "Datasheet" "https://www.bourns.com/docs/product-datasheets/cr.pdf"
				(at 20.32 -17.78 0)
				(effects
					(font
						(size 1.27 1.27)
						(thickness 0.15)
					)
					(justify left bottom)
					(hide yes)
				)
			)
			(property "Description" "SMD Chip Resistor, 10 kohm, ± 1%, 62.5 mW, 0402 [1005 Metric], Thick Film, General Purpose"
				(at 0 0 0)
				(effects
					(font
						(size 1.27 1.27)
					)
					(hide yes)
				)
			)
			(property "MPN" "CR0402-FX-1002GLF"
				(at 20.32 -20.32 0)
				(effects
					(font
						(size 1.27 1.27)
						(thickness 0.15)
					)
					(justify left bottom)
					(hide yes)
				)
			)
			(property "Manufacturer" "Bourns"
				(at 20.32 -22.86 0)
				(effects
					(font
						(size 1.27 1.27)
						(thickness 0.15)
					)
					(justify left bottom)
					(hide yes)
				)
			)
			(property "License" "Apache-2.0"
				(at 20.32 -25.4 0)
				(effects
					(font
						(size 1.27 1.27)
						(thickness 0.15)
					)
					(justify left bottom)
					(hide yes)
				)
			)
			(property "Author" "Antmicro"
				(at 20.32 -27.94 0)
				(effects
					(font
						(size 1.27 1.27)
						(thickness 0.15)
					)
					(justify left bottom)
					(hide yes)
				)
			)
			(property "Val" "10k"
				(at 20.32 -7.62 0)
				(effects
					(font
						(size 1.27 1.27)
						(thickness 0.15)
					)
					(justify left bottom)
				)
			)
			(property "Tolerance" "1%"
				(at 20.32 -10.16 0)
				(effects
					(font
						(size 1.27 1.27)
					)
					(justify left bottom)
					(hide yes)
				)
			)
			(property "ki_keywords" "0402, SMT, RESISTOR, PASSIVE"
				(at 0 0 0)
				(effects
					(font
						(size 1.27 1.27)
					)
					(hide yes)
				)
			)
			(symbol "R_10k_0402_0_1"
				(rectangle
					(start 0.635 0.889)
					(end 4.445 -0.889)
					(stroke
						(width 0.254)
						(type default)
					)
					(fill
						(type none)
					)
				)
			)
			(symbol "R_10k_0402_1_1"
				(pin passive line
					(at 0 0 0)
					(length 0.635)
					(name "~"
						(effects
							(font
								(size 1.27 1.27)
							)
						)
					)
					(number "1"
						(effects
							(font
								(size 1.27 1.27)
							)
						)
					)
				)
				(pin passive line
					(at 5.08 0 180)
					(length 0.635)
					(name "~"
						(effects
							(font
								(size 1.27 1.27)
							)
						)
					)
					(number "2"
						(effects
							(font
								(size 1.27 1.27)
							)
						)
					)
				)
			)
		)
	(symbol "antmicroResistors0402:R_110k_0402"
			(pin_numbers hide)
			(pin_names hide)
			(exclude_from_sim no)
			(in_bom yes)
			(on_board yes)
			(property "Reference" "R"
				(at 20.32 -5.08 0)
				(effects
					(font
						(size 1.27 1.27)
						(thickness 0.15)
					)
					(justify left bottom)
				)
			)
			(property "Value" "R_110k_0402"
				(at 20.32 -12.7 0)
				(effects
					(font
						(size 1.27 1.27)
						(thickness 0.15)
					)
					(justify left bottom)
					(hide yes)
				)
			)
			(property "Footprint" "antmicro-footprints:R_0402_1005Metric"
				(at 20.32 -15.24 0)
				(effects
					(font
						(size 1.27 1.27)
						(thickness 0.15)
					)
					(justify left bottom)
					(hide yes)
				)
			)
			(property "Datasheet" "https://www.bourns.com/docs/product-datasheets/cr.pdf"
				(at 20.32 -17.78 0)
				(effects
					(font
						(size 1.27 1.27)
						(thickness 0.15)
					)
					(justify left bottom)
					(hide yes)
				)
			)
			(property "Description" "SMD Chip Resistor, 110 kohm, ± 1%, 63 mW, 0402 [1005 Metric], Thick Film, General Purpose"
				(at 0 0 0)
				(effects
					(font
						(size 1.27 1.27)
					)
					(hide yes)
				)
			)
			(property "MPN" "CR0402-FX-1103GLF"
				(at 20.32 -20.32 0)
				(effects
					(font
						(size 1.27 1.27)
						(thickness 0.15)
					)
					(justify left bottom)
					(hide yes)
				)
			)
			(property "Manufacturer" "Bourns"
				(at 20.32 -22.86 0)
				(effects
					(font
						(size 1.27 1.27)
						(thickness 0.15)
					)
					(justify left bottom)
					(hide yes)
				)
			)
			(property "License" "Apache-2.0"
				(at 20.32 -25.4 0)
				(effects
					(font
						(size 1.27 1.27)
						(thickness 0.15)
					)
					(justify left bottom)
					(hide yes)
				)
			)
			(property "Author" "Antmicro"
				(at 20.32 -27.94 0)
				(effects
					(font
						(size 1.27 1.27)
						(thickness 0.15)
					)
					(justify left bottom)
					(hide yes)
				)
			)
			(property "Val" "110k"
				(at 20.32 -7.62 0)
				(effects
					(font
						(size 1.27 1.27)
						(thickness 0.15)
					)
					(justify left bottom)
				)
			)
			(property "Tolerance" "1%"
				(at 20.32 -10.16 0)
				(effects
					(font
						(size 1.27 1.27)
					)
					(justify left bottom)
					(hide yes)
				)
			)
			(property "ki_keywords" "0402, SMT, RESISTOR, PASSIVE"
				(at 0 0 0)
				(effects
					(font
						(size 1.27 1.27)
					)
					(hide yes)
				)
			)
			(symbol "R_110k_0402_0_1"
				(rectangle
					(start 0.635 0.889)
					(end 4.445 -0.889)
					(stroke
						(width 0.254)
						(type default)
					)
					(fill
						(type none)
					)
				)
			)
			(symbol "R_110k_0402_1_1"
				(pin passive line
					(at 0 0 0)
					(length 0.635)
					(name "~"
						(effects
							(font
								(size 1.27 1.27)
							)
						)
					)
					(number "1"
						(effects
							(font
								(size 1.27 1.27)
							)
						)
					)
				)
				(pin passive line
					(at 5.08 0 180)
					(length 0.635)
					(name "~"
						(effects
							(font
								(size 1.27 1.27)
							)
						)
					)
					(number "2"
						(effects
							(font
								(size 1.27 1.27)
							)
						)
					)
				)
			)
		)
	(symbol "antmicroResistors0402:R_124k_0402"
			(pin_numbers hide)
			(pin_names hide)
			(exclude_from_sim no)
			(in_bom yes)
			(on_board yes)
			(property "Reference" "R"
				(at 20.32 -5.08 0)
				(effects
					(font
						(size 1.27 1.27)
						(thickness 0.15)
					)
					(justify left bottom)
				)
			)
			(property "Value" "R_124k_0402"
				(at 20.32 -12.7 0)
				(effects
					(font
						(size 1.27 1.27)
						(thickness 0.15)
					)
					(justify left bottom)
					(hide yes)
				)
			)
			(property "Footprint" "antmicro-footprints:R_0402_1005Metric"
				(at 20.32 -15.24 0)
				(effects
					(font
						(size 1.27 1.27)
						(thickness 0.15)
					)
					(justify left bottom)
					(hide yes)
				)
			)
			(property "Datasheet" "https://www.bourns.com/docs/product-datasheets/cr.pdf"
				(at 20.32 -17.78 0)
				(effects
					(font
						(size 1.27 1.27)
						(thickness 0.15)
					)
					(justify left bottom)
					(hide yes)
				)
			)
			(property "Description" "SMD Chip Resistor, 124 kohm, ± 1%, 100 mW, 0402 [1005 Metric], Thick Film, Precision"
				(at 0 0 0)
				(effects
					(font
						(size 1.27 1.27)
					)
					(hide yes)
				)
			)
			(property "MPN" "CR0402-FX-1243GLF"
				(at 20.32 -20.32 0)
				(effects
					(font
						(size 1.27 1.27)
						(thickness 0.15)
					)
					(justify left bottom)
					(hide yes)
				)
			)
			(property "Manufacturer" "Bourns"
				(at 20.32 -22.86 0)
				(effects
					(font
						(size 1.27 1.27)
						(thickness 0.15)
					)
					(justify left bottom)
					(hide yes)
				)
			)
			(property "License" "Apache-2.0"
				(at 20.32 -25.4 0)
				(effects
					(font
						(size 1.27 1.27)
						(thickness 0.15)
					)
					(justify left bottom)
					(hide yes)
				)
			)
			(property "Author" "Antmicro"
				(at 20.32 -27.94 0)
				(effects
					(font
						(size 1.27 1.27)
						(thickness 0.15)
					)
					(justify left bottom)
					(hide yes)
				)
			)
			(property "Val" "124k"
				(at 20.32 -7.62 0)
				(effects
					(font
						(size 1.27 1.27)
						(thickness 0.15)
					)
					(justify left bottom)
				)
			)
			(property "Tolerance" "1%"
				(at 20.32 -10.16 0)
				(effects
					(font
						(size 1.27 1.27)
					)
					(justify left bottom)
					(hide yes)
				)
			)
			(property "ki_keywords" "0402, SMT, RESISTOR, PASSIVE"
				(at 0 0 0)
				(effects
					(font
						(size 1.27 1.27)
					)
					(hide yes)
				)
			)
			(symbol "R_124k_0402_0_1"
				(rectangle
					(start 0.635 0.889)
					(end 4.445 -0.889)
					(stroke
						(width 0.254)
						(type default)
					)
					(fill
						(type none)
					)
				)
			)
			(symbol "R_124k_0402_1_1"
				(pin passive line
					(at 0 0 0)
					(length 0.635)
					(name "~"
						(effects
							(font
								(size 1.27 1.27)
							)
						)
					)
					(number "1"
						(effects
							(font
								(size 1.27 1.27)
							)
						)
					)
				)
				(pin passive line
					(at 5.08 0 180)
					(length 0.635)
					(name "~"
						(effects
							(font
								(size 1.27 1.27)
							)
						)
					)
					(number "2"
						(effects
							(font
								(size 1.27 1.27)
							)
						)
					)
				)
			)
		)
	(symbol "antmicroResistors0402:R_12k_0402"
			(pin_numbers hide)
			(pin_names hide)
			(exclude_from_sim no)
			(in_bom yes)
			(on_board yes)
			(property "Reference" "R"
				(at 20.32 -5.08 0)
				(effects
					(font
						(size 1.27 1.27)
						(thickness 0.15)
					)
					(justify left bottom)
				)
			)
			(property "Value" "R_12k_0402"
				(at 20.32 -12.7 0)
				(effects
					(font
						(size 1.27 1.27)
						(thickness 0.15)
					)
					(justify left bottom)
					(hide yes)
				)
			)
			(property "Footprint" "antmicro-footprints:R_0402_1005Metric"
				(at 20.32 -15.24 0)
				(effects
					(font
						(size 1.27 1.27)
						(thickness 0.15)
					)
					(justify left bottom)
					(hide yes)
				)
			)
			(property "Datasheet" "https://www.bourns.com/docs/product-datasheets/cr.pdf"
				(at 20.32 -17.78 0)
				(effects
					(font
						(size 1.27 1.27)
						(thickness 0.15)
					)
					(justify left bottom)
					(hide yes)
				)
			)
			(property "Description" "SMD Chip Resistor, 12 kohm, ± 1%, 62.5 mW, 0402 [1005 Metric], Thick Film, General Purpose"
				(at 0 0 0)
				(effects
					(font
						(size 1.27 1.27)
					)
					(hide yes)
				)
			)
			(property "MPN" "CR0402-FX-1202GLF"
				(at 20.32 -20.32 0)
				(effects
					(font
						(size 1.27 1.27)
						(thickness 0.15)
					)
					(justify left bottom)
					(hide yes)
				)
			)
			(property "Manufacturer" "Bourns"
				(at 20.32 -22.86 0)
				(effects
					(font
						(size 1.27 1.27)
						(thickness 0.15)
					)
					(justify left bottom)
					(hide yes)
				)
			)
			(property "License" "Apache-2.0"
				(at 20.32 -25.4 0)
				(effects
					(font
						(size 1.27 1.27)
						(thickness 0.15)
					)
					(justify left bottom)
					(hide yes)
				)
			)
			(property "Author" "Antmicro"
				(at 20.32 -27.94 0)
				(effects
					(font
						(size 1.27 1.27)
						(thickness 0.15)
					)
					(justify left bottom)
					(hide yes)
				)
			)
			(property "Val" "12k"
				(at 20.32 -7.62 0)
				(effects
					(font
						(size 1.27 1.27)
						(thickness 0.15)
					)
					(justify left bottom)
				)
			)
			(property "Tolerance" "1%"
				(at 20.32 -10.16 0)
				(effects
					(font
						(size 1.27 1.27)
					)
					(justify left bottom)
					(hide yes)
				)
			)
			(property "ki_keywords" "0402, SMT, RESISTOR, PASSIVE"
				(at 0 0 0)
				(effects
					(font
						(size 1.27 1.27)
					)
					(hide yes)
				)
			)
			(symbol "R_12k_0402_0_1"
				(rectangle
					(start 0.635 0.889)
					(end 4.445 -0.889)
					(stroke
						(width 0.254)
						(type default)
					)
					(fill
						(type none)
					)
				)
			)
			(symbol "R_12k_0402_1_1"
				(pin passive line
					(at 0 0 0)
					(length 0.635)
					(name "~"
						(effects
							(font
								(size 1.27 1.27)
							)
						)
					)
					(number "1"
						(effects
							(font
								(size 1.27 1.27)
							)
						)
					)
				)
				(pin passive line
					(at 5.08 0 180)
					(length 0.635)
					(name "~"
						(effects
							(font
								(size 1.27 1.27)
							)
						)
					)
					(number "2"
						(effects
							(font
								(size 1.27 1.27)
							)
						)
					)
				)
			)
		)
	(symbol "antmicroResistors0402:R_14k_0402"
			(pin_numbers hide)
			(pin_names hide)
			(exclude_from_sim no)
			(in_bom yes)
			(on_board yes)
			(property "Reference" "R"
				(at 20.32 -5.08 0)
				(effects
					(font
						(size 1.27 1.27)
						(thickness 0.15)
					)
					(justify left bottom)
				)
			)
			(property "Value" "R_14k_0402"
				(at 20.32 -12.7 0)
				(effects
					(font
						(size 1.27 1.27)
						(thickness 0.15)
					)
					(justify left bottom)
					(hide yes)
				)
			)
			(property "Footprint" "antmicro-footprints:R_0402_1005Metric"
				(at 20.32 -15.24 0)
				(effects
					(font
						(size 1.27 1.27)
						(thickness 0.15)
					)
					(justify left bottom)
					(hide yes)
				)
			)
			(property "Datasheet" "https://www.bourns.com/docs/product-datasheets/cr.pdf"
				(at 20.32 -17.78 0)
				(effects
					(font
						(size 1.27 1.27)
						(thickness 0.15)
					)
					(justify left bottom)
					(hide yes)
				)
			)
			(property "Description" "SMD Chip Resistor, 14 kohm, ± 1%, 100 mW, 0402 [1005 Metric], Thick Film, Precision"
				(at 0 0 0)
				(effects
					(font
						(size 1.27 1.27)
					)
					(hide yes)
				)
			)
			(property "MPN" "CR0402-FX-1402GLF"
				(at 20.32 -20.32 0)
				(effects
					(font
						(size 1.27 1.27)
						(thickness 0.15)
					)
					(justify left bottom)
					(hide yes)
				)
			)
			(property "Manufacturer" "Bourns"
				(at 20.32 -22.86 0)
				(effects
					(font
						(size 1.27 1.27)
						(thickness 0.15)
					)
					(justify left bottom)
					(hide yes)
				)
			)
			(property "License" "Apache-2.0"
				(at 20.32 -25.4 0)
				(effects
					(font
						(size 1.27 1.27)
						(thickness 0.15)
					)
					(justify left bottom)
					(hide yes)
				)
			)
			(property "Author" "Antmicro"
				(at 20.32 -27.94 0)
				(effects
					(font
						(size 1.27 1.27)
						(thickness 0.15)
					)
					(justify left bottom)
					(hide yes)
				)
			)
			(property "Val" "14k"
				(at 20.32 -7.62 0)
				(effects
					(font
						(size 1.27 1.27)
						(thickness 0.15)
					)
					(justify left bottom)
				)
			)
			(property "Tolerance" "1%"
				(at 20.32 -10.16 0)
				(effects
					(font
						(size 1.27 1.27)
					)
					(justify left bottom)
					(hide yes)
				)
			)
			(property "ki_keywords" "0402, SMT, RESISTOR, PASSIVE"
				(at 0 0 0)
				(effects
					(font
						(size 1.27 1.27)
					)
					(hide yes)
				)
			)
			(symbol "R_14k_0402_0_1"
				(rectangle
					(start 0.635 0.889)
					(end 4.445 -0.889)
					(stroke
						(width 0.254)
						(type default)
					)
					(fill
						(type none)
					)
				)
			)
			(symbol "R_14k_0402_1_1"
				(pin passive line
					(at 0 0 0)
					(length 0.635)
					(name "~"
						(effects
							(font
								(size 1.27 1.27)
							)
						)
					)
					(number "1"
						(effects
							(font
								(size 1.27 1.27)
							)
						)
					)
				)
				(pin passive line
					(at 5.08 0 180)
					(length 0.635)
					(name "~"
						(effects
							(font
								(size 1.27 1.27)
							)
						)
					)
					(number "2"
						(effects
							(font
								(size 1.27 1.27)
							)
						)
					)
				)
			)
		)
	(symbol "antmicroResistors0402:R_15k_0.1%_0402"
			(pin_numbers hide)
			(pin_names hide)
			(exclude_from_sim no)
			(in_bom yes)
			(on_board yes)
			(property "Reference" "R"
				(at 20.32 -5.08 0)
				(effects
					(font
						(size 1.27 1.27)
						(thickness 0.15)
					)
					(justify left bottom)
				)
			)
			(property "Value" "R_15k_0.1%_0402"
				(at 20.32 -12.7 0)
				(effects
					(font
						(size 1.27 1.27)
						(thickness 0.15)
					)
					(justify left bottom)
					(hide yes)
				)
			)
			(property "Footprint" "antmicro-footprints:R_0402_1005Metric"
				(at 20.32 -15.24 0)
				(effects
					(font
						(size 1.27 1.27)
						(thickness 0.15)
					)
					(justify left bottom)
					(hide yes)
				)
			)
			(property "Datasheet" "https://www.mouser.com/datasheet/2/315/AOA0000C307-1149632.pdf"
				(at 20.32 -17.78 0)
				(effects
					(font
						(size 1.27 1.27)
						(thickness 0.15)
					)
					(justify left bottom)
					(hide yes)
				)
			)
			(property "Description" "SMD Chip Resistor, 15 kohm, ± 0.1%, 62.5 mW, 0402 [1005 Metric], Metal Film (Thin Film)"
				(at 0 0 0)
				(effects
					(font
						(size 1.27 1.27)
					)
					(hide yes)
				)
			)
			(property "MPN" "ERA-2ARB153X"
				(at 20.32 -20.32 0)
				(effects
					(font
						(size 1.27 1.27)
						(thickness 0.15)
					)
					(justify left bottom)
					(hide yes)
				)
			)
			(property "Manufacturer" "Panasonic"
				(at 20.32 -22.86 0)
				(effects
					(font
						(size 1.27 1.27)
						(thickness 0.15)
					)
					(justify left bottom)
					(hide yes)
				)
			)
			(property "License" "Apache-2.0"
				(at 20.32 -25.4 0)
				(effects
					(font
						(size 1.27 1.27)
						(thickness 0.15)
					)
					(justify left bottom)
					(hide yes)
				)
			)
			(property "Author" "Antmicro"
				(at 20.32 -27.94 0)
				(effects
					(font
						(size 1.27 1.27)
						(thickness 0.15)
					)
					(justify left bottom)
					(hide yes)
				)
			)
			(property "Val" "15k"
				(at 20.32 -7.62 0)
				(effects
					(font
						(size 1.27 1.27)
						(thickness 0.15)
					)
					(justify left bottom)
				)
			)
			(property "Tolerance" "0.1%"
				(at 20.32 -10.16 0)
				(effects
					(font
						(size 1.27 1.27)
					)
					(justify left bottom)
					(hide yes)
				)
			)
			(property "ki_keywords" "0402, SMT, RESISTOR, PASSIVE"
				(at 0 0 0)
				(effects
					(font
						(size 1.27 1.27)
					)
					(hide yes)
				)
			)
			(symbol "R_15k_0.1%_0402_0_1"
				(rectangle
					(start 0.635 0.889)
					(end 4.445 -0.889)
					(stroke
						(width 0.254)
						(type default)
					)
					(fill
						(type none)
					)
				)
			)
			(symbol "R_15k_0.1%_0402_1_1"
				(pin passive line
					(at 0 0 0)
					(length 0.635)
					(name "~"
						(effects
							(font
								(size 1.27 1.27)
							)
						)
					)
					(number "1"
						(effects
							(font
								(size 1.27 1.27)
							)
						)
					)
				)
				(pin passive line
					(at 5.08 0 180)
					(length 0.635)
					(name "~"
						(effects
							(font
								(size 1.27 1.27)
							)
						)
					)
					(number "2"
						(effects
							(font
								(size 1.27 1.27)
							)
						)
					)
				)
			)
		)
	(symbol "antmicroResistors0402:R_1M_0402"
			(pin_numbers hide)
			(pin_names hide)
			(exclude_from_sim no)
			(in_bom yes)
			(on_board yes)
			(property "Reference" "R"
				(at 20.32 -5.08 0)
				(effects
					(font
						(size 1.27 1.27)
						(thickness 0.15)
					)
					(justify left bottom)
				)
			)
			(property "Value" "R_1M_0402"
				(at 20.32 -12.7 0)
				(effects
					(font
						(size 1.27 1.27)
						(thickness 0.15)
					)
					(justify left bottom)
					(hide yes)
				)
			)
			(property "Footprint" "antmicro-footprints:R_0402_1005Metric"
				(at 20.32 -15.24 0)
				(effects
					(font
						(size 1.27 1.27)
						(thickness 0.15)
					)
					(justify left bottom)
					(hide yes)
				)
			)
			(property "Datasheet" "https://www.bourns.com/docs/product-datasheets/cr.pdf"
				(at 20.32 -17.78 0)
				(effects
					(font
						(size 1.27 1.27)
						(thickness 0.15)
					)
					(justify left bottom)
					(hide yes)
				)
			)
			(property "Description" "SMD Chip Resistor, 1 Mohm, ± 1%, 62.5 mW, 0402 [1005 Metric], Thick Film, General Purpose"
				(at 0 0 0)
				(effects
					(font
						(size 1.27 1.27)
					)
					(hide yes)
				)
			)
			(property "MPN" "CR0402-FX-1004GLF"
				(at 20.32 -20.32 0)
				(effects
					(font
						(size 1.27 1.27)
						(thickness 0.15)
					)
					(justify left bottom)
					(hide yes)
				)
			)
			(property "Manufacturer" "Bourns"
				(at 20.32 -22.86 0)
				(effects
					(font
						(size 1.27 1.27)
						(thickness 0.15)
					)
					(justify left bottom)
					(hide yes)
				)
			)
			(property "License" "Apache-2.0"
				(at 20.32 -25.4 0)
				(effects
					(font
						(size 1.27 1.27)
						(thickness 0.15)
					)
					(justify left bottom)
					(hide yes)
				)
			)
			(property "Author" "Antmicro"
				(at 20.32 -27.94 0)
				(effects
					(font
						(size 1.27 1.27)
						(thickness 0.15)
					)
					(justify left bottom)
					(hide yes)
				)
			)
			(property "Val" "1M"
				(at 20.32 -7.62 0)
				(effects
					(font
						(size 1.27 1.27)
						(thickness 0.15)
					)
					(justify left bottom)
				)
			)
			(property "Tolerance" "1%"
				(at 20.32 -10.16 0)
				(effects
					(font
						(size 1.27 1.27)
					)
					(justify left bottom)
					(hide yes)
				)
			)
			(property "ki_keywords" "0402, SMT, RESISTOR, PASSIVE"
				(at 0 0 0)
				(effects
					(font
						(size 1.27 1.27)
					)
					(hide yes)
				)
			)
			(symbol "R_1M_0402_0_1"
				(rectangle
					(start 0.635 0.889)
					(end 4.445 -0.889)
					(stroke
						(width 0.254)
						(type default)
					)
					(fill
						(type none)
					)
				)
			)
			(symbol "R_1M_0402_1_1"
				(pin passive line
					(at 0 0 0)
					(length 0.635)
					(name "~"
						(effects
							(font
								(size 1.27 1.27)
							)
						)
					)
					(number "1"
						(effects
							(font
								(size 1.27 1.27)
							)
						)
					)
				)
				(pin passive line
					(at 5.08 0 180)
					(length 0.635)
					(name "~"
						(effects
							(font
								(size 1.27 1.27)
							)
						)
					)
					(number "2"
						(effects
							(font
								(size 1.27 1.27)
							)
						)
					)
				)
			)
		)
	(symbol "antmicroResistors0402:R_1k_0402"
			(pin_numbers hide)
			(pin_names hide)
			(exclude_from_sim no)
			(in_bom yes)
			(on_board yes)
			(property "Reference" "R"
				(at 20.32 -5.08 0)
				(effects
					(font
						(size 1.27 1.27)
						(thickness 0.15)
					)
					(justify left bottom)
				)
			)
			(property "Value" "R_1k_0402"
				(at 20.32 -12.7 0)
				(effects
					(font
						(size 1.27 1.27)
						(thickness 0.15)
					)
					(justify left bottom)
					(hide yes)
				)
			)
			(property "Footprint" "antmicro-footprints:R_0402_1005Metric"
				(at 20.32 -15.24 0)
				(effects
					(font
						(size 1.27 1.27)
						(thickness 0.15)
					)
					(justify left bottom)
					(hide yes)
				)
			)
			(property "Datasheet" "https://www.bourns.com/docs/product-datasheets/cr.pdf"
				(at 20.32 -17.78 0)
				(effects
					(font
						(size 1.27 1.27)
						(thickness 0.15)
					)
					(justify left bottom)
					(hide yes)
				)
			)
			(property "Description" "SMD Chip Resistor, 1 kohm, ± 1%, 63 mW, 0402 [1005 Metric], Thick Film, General Purpose"
				(at 0 0 0)
				(effects
					(font
						(size 1.27 1.27)
					)
					(hide yes)
				)
			)
			(property "MPN" "CR0402-FX-1001GLF"
				(at 20.32 -20.32 0)
				(effects
					(font
						(size 1.27 1.27)
						(thickness 0.15)
					)
					(justify left bottom)
					(hide yes)
				)
			)
			(property "Manufacturer" "Bourns"
				(at 20.32 -22.86 0)
				(effects
					(font
						(size 1.27 1.27)
						(thickness 0.15)
					)
					(justify left bottom)
					(hide yes)
				)
			)
			(property "License" "Apache-2.0"
				(at 20.32 -25.4 0)
				(effects
					(font
						(size 1.27 1.27)
						(thickness 0.15)
					)
					(justify left bottom)
					(hide yes)
				)
			)
			(property "Author" "Antmicro"
				(at 20.32 -27.94 0)
				(effects
					(font
						(size 1.27 1.27)
						(thickness 0.15)
					)
					(justify left bottom)
					(hide yes)
				)
			)
			(property "Val" "1k"
				(at 20.32 -7.62 0)
				(effects
					(font
						(size 1.27 1.27)
						(thickness 0.15)
					)
					(justify left bottom)
				)
			)
			(property "Tolerance" "1%"
				(at 20.32 -10.16 0)
				(effects
					(font
						(size 1.27 1.27)
					)
					(justify left bottom)
					(hide yes)
				)
			)
			(property "ki_keywords" "0402, SMT, RESISTOR, PASSIVE"
				(at 0 0 0)
				(effects
					(font
						(size 1.27 1.27)
					)
					(hide yes)
				)
			)
			(symbol "R_1k_0402_0_1"
				(rectangle
					(start 0.635 0.889)
					(end 4.445 -0.889)
					(stroke
						(width 0.254)
						(type default)
					)
					(fill
						(type none)
					)
				)
			)
			(symbol "R_1k_0402_1_1"
				(pin passive line
					(at 0 0 0)
					(length 0.635)
					(name "~"
						(effects
							(font
								(size 1.27 1.27)
							)
						)
					)
					(number "1"
						(effects
							(font
								(size 1.27 1.27)
							)
						)
					)
				)
				(pin passive line
					(at 5.08 0 180)
					(length 0.635)
					(name "~"
						(effects
							(font
								(size 1.27 1.27)
							)
						)
					)
					(number "2"
						(effects
							(font
								(size 1.27 1.27)
							)
						)
					)
				)
			)
		)
	(symbol "antmicroResistors0402:R_24k_0402"
			(pin_numbers hide)
			(pin_names hide)
			(exclude_from_sim no)
			(in_bom yes)
			(on_board yes)
			(property "Reference" "R"
				(at 20.32 -5.08 0)
				(effects
					(font
						(size 1.27 1.27)
						(thickness 0.15)
					)
					(justify left bottom)
				)
			)
			(property "Value" "R_24k_0402"
				(at 20.32 -12.7 0)
				(effects
					(font
						(size 1.27 1.27)
						(thickness 0.15)
					)
					(justify left bottom)
					(hide yes)
				)
			)
			(property "Footprint" "antmicro-footprints:R_0402_1005Metric"
				(at 20.32 -15.24 0)
				(effects
					(font
						(size 1.27 1.27)
						(thickness 0.15)
					)
					(justify left bottom)
					(hide yes)
				)
			)
			(property "Datasheet" "https://www.bourns.com/docs/product-datasheets/cr.pdf"
				(at 20.32 -17.78 0)
				(effects
					(font
						(size 1.27 1.27)
						(thickness 0.15)
					)
					(justify left bottom)
					(hide yes)
				)
			)
			(property "Description" "SMD Chip Resistor, 24 kohm, ± 1%, 100 mW, 0402 [1005 Metric], Thick Film, Precision"
				(at 0 0 0)
				(effects
					(font
						(size 1.27 1.27)
					)
					(hide yes)
				)
			)
			(property "MPN" "CR0402-FX-2402GLF"
				(at 20.32 -20.32 0)
				(effects
					(font
						(size 1.27 1.27)
						(thickness 0.15)
					)
					(justify left bottom)
					(hide yes)
				)
			)
			(property "Manufacturer" "Bourns"
				(at 20.32 -22.86 0)
				(effects
					(font
						(size 1.27 1.27)
						(thickness 0.15)
					)
					(justify left bottom)
					(hide yes)
				)
			)
			(property "License" "Apache-2.0"
				(at 20.32 -25.4 0)
				(effects
					(font
						(size 1.27 1.27)
						(thickness 0.15)
					)
					(justify left bottom)
					(hide yes)
				)
			)
			(property "Author" "Antmicro"
				(at 20.32 -27.94 0)
				(effects
					(font
						(size 1.27 1.27)
						(thickness 0.15)
					)
					(justify left bottom)
					(hide yes)
				)
			)
			(property "Val" "24k"
				(at 20.32 -7.62 0)
				(effects
					(font
						(size 1.27 1.27)
						(thickness 0.15)
					)
					(justify left bottom)
				)
			)
			(property "Tolerance" "1%"
				(at 20.32 -10.16 0)
				(effects
					(font
						(size 1.27 1.27)
					)
					(justify left bottom)
					(hide yes)
				)
			)
			(property "ki_keywords" "0402, SMT, RESISTOR, PASSIVE"
				(at 0 0 0)
				(effects
					(font
						(size 1.27 1.27)
					)
					(hide yes)
				)
			)
			(symbol "R_24k_0402_0_1"
				(rectangle
					(start 0.635 0.889)
					(end 4.445 -0.889)
					(stroke
						(width 0.254)
						(type default)
					)
					(fill
						(type none)
					)
				)
			)
			(symbol "R_24k_0402_1_1"
				(pin passive line
					(at 0 0 0)
					(length 0.635)
					(name "~"
						(effects
							(font
								(size 1.27 1.27)
							)
						)
					)
					(number "1"
						(effects
							(font
								(size 1.27 1.27)
							)
						)
					)
				)
				(pin passive line
					(at 5.08 0 180)
					(length 0.635)
					(name "~"
						(effects
							(font
								(size 1.27 1.27)
							)
						)
					)
					(number "2"
						(effects
							(font
								(size 1.27 1.27)
							)
						)
					)
				)
			)
		)
	(symbol "antmicroResistors0402:R_2k2_0402"
			(pin_numbers hide)
			(pin_names hide)
			(exclude_from_sim no)
			(in_bom yes)
			(on_board yes)
			(property "Reference" "R"
				(at 20.32 -5.08 0)
				(effects
					(font
						(size 1.27 1.27)
						(thickness 0.15)
					)
					(justify left bottom)
				)
			)
			(property "Value" "R_2k2_0402"
				(at 20.32 -12.7 0)
				(effects
					(font
						(size 1.27 1.27)
						(thickness 0.15)
					)
					(justify left bottom)
					(hide yes)
				)
			)
			(property "Footprint" "antmicro-footprints:R_0402_1005Metric"
				(at 20.32 -15.24 0)
				(effects
					(font
						(size 1.27 1.27)
						(thickness 0.15)
					)
					(justify left bottom)
					(hide yes)
				)
			)
			(property "Datasheet" "https://www.bourns.com/docs/product-datasheets/cr.pdf"
				(at 20.32 -17.78 0)
				(effects
					(font
						(size 1.27 1.27)
						(thickness 0.15)
					)
					(justify left bottom)
					(hide yes)
				)
			)
			(property "Description" "SMD Chip Resistor, 2.2 kohm, ± 1%, 62.5 mW, 0402 [1005 Metric], Thick Film, General Purpose"
				(at 0 0 0)
				(effects
					(font
						(size 1.27 1.27)
					)
					(hide yes)
				)
			)
			(property "MPN" "CR0402-FX-2201GLF"
				(at 20.32 -20.32 0)
				(effects
					(font
						(size 1.27 1.27)
						(thickness 0.15)
					)
					(justify left bottom)
					(hide yes)
				)
			)
			(property "Manufacturer" "Bourns"
				(at 20.32 -22.86 0)
				(effects
					(font
						(size 1.27 1.27)
						(thickness 0.15)
					)
					(justify left bottom)
					(hide yes)
				)
			)
			(property "License" "Apache-2.0"
				(at 20.32 -25.4 0)
				(effects
					(font
						(size 1.27 1.27)
						(thickness 0.15)
					)
					(justify left bottom)
					(hide yes)
				)
			)
			(property "Author" "Antmicro"
				(at 20.32 -27.94 0)
				(effects
					(font
						(size 1.27 1.27)
						(thickness 0.15)
					)
					(justify left bottom)
					(hide yes)
				)
			)
			(property "Val" "2k2"
				(at 20.32 -7.62 0)
				(effects
					(font
						(size 1.27 1.27)
						(thickness 0.15)
					)
					(justify left bottom)
				)
			)
			(property "Tolerance" "1%"
				(at 20.32 -10.16 0)
				(effects
					(font
						(size 1.27 1.27)
					)
					(justify left bottom)
					(hide yes)
				)
			)
			(property "ki_keywords" "0402, SMT, RESISTOR, PASSIVE"
				(at 0 0 0)
				(effects
					(font
						(size 1.27 1.27)
					)
					(hide yes)
				)
			)
			(symbol "R_2k2_0402_0_1"
				(rectangle
					(start 0.635 0.889)
					(end 4.445 -0.889)
					(stroke
						(width 0.254)
						(type default)
					)
					(fill
						(type none)
					)
				)
			)
			(symbol "R_2k2_0402_1_1"
				(pin passive line
					(at 0 0 0)
					(length 0.635)
					(name "~"
						(effects
							(font
								(size 1.27 1.27)
							)
						)
					)
					(number "1"
						(effects
							(font
								(size 1.27 1.27)
							)
						)
					)
				)
				(pin passive line
					(at 5.08 0 180)
					(length 0.635)
					(name "~"
						(effects
							(font
								(size 1.27 1.27)
							)
						)
					)
					(number "2"
						(effects
							(font
								(size 1.27 1.27)
							)
						)
					)
				)
			)
		)
	(symbol "antmicroResistors0402:R_330R_0402"
			(pin_numbers hide)
			(pin_names hide)
			(exclude_from_sim no)
			(in_bom yes)
			(on_board yes)
			(property "Reference" "R"
				(at 20.32 -5.08 0)
				(effects
					(font
						(size 1.27 1.27)
						(thickness 0.15)
					)
					(justify left bottom)
				)
			)
			(property "Value" "R_330R_0402"
				(at 20.32 -12.7 0)
				(effects
					(font
						(size 1.27 1.27)
						(thickness 0.15)
					)
					(justify left bottom)
					(hide yes)
				)
			)
			(property "Footprint" "antmicro-footprints:R_0402_1005Metric"
				(at 20.32 -15.24 0)
				(effects
					(font
						(size 1.27 1.27)
						(thickness 0.15)
					)
					(justify left bottom)
					(hide yes)
				)
			)
			(property "Datasheet" "https://www.bourns.com/docs/product-datasheets/cr.pdf"
				(at 20.32 -17.78 0)
				(effects
					(font
						(size 1.27 1.27)
						(thickness 0.15)
					)
					(justify left bottom)
					(hide yes)
				)
			)
			(property "Description" "SMD Chip Resistor, 330 ohm, ± 1%, 62.5 mW, 0402 [1005 Metric], Thick Film, General Purpose"
				(at 0 0 0)
				(effects
					(font
						(size 1.27 1.27)
					)
					(hide yes)
				)
			)
			(property "MPN" "CR0402-FX-3300GLF"
				(at 20.32 -20.32 0)
				(effects
					(font
						(size 1.27 1.27)
						(thickness 0.15)
					)
					(justify left bottom)
					(hide yes)
				)
			)
			(property "Manufacturer" "Bourns"
				(at 20.32 -22.86 0)
				(effects
					(font
						(size 1.27 1.27)
						(thickness 0.15)
					)
					(justify left bottom)
					(hide yes)
				)
			)
			(property "License" "Apache-2.0"
				(at 20.32 -25.4 0)
				(effects
					(font
						(size 1.27 1.27)
						(thickness 0.15)
					)
					(justify left bottom)
					(hide yes)
				)
			)
			(property "Author" "Antmicro"
				(at 20.32 -27.94 0)
				(effects
					(font
						(size 1.27 1.27)
						(thickness 0.15)
					)
					(justify left bottom)
					(hide yes)
				)
			)
			(property "Val" "330R"
				(at 20.32 -7.62 0)
				(effects
					(font
						(size 1.27 1.27)
						(thickness 0.15)
					)
					(justify left bottom)
				)
			)
			(property "Tolerance" "1%"
				(at 20.32 -10.16 0)
				(effects
					(font
						(size 1.27 1.27)
					)
					(justify left bottom)
					(hide yes)
				)
			)
			(property "ki_keywords" "0402, SMT, RESISTOR, PASSIVE"
				(at 0 0 0)
				(effects
					(font
						(size 1.27 1.27)
					)
					(hide yes)
				)
			)
			(symbol "R_330R_0402_0_1"
				(rectangle
					(start 0.635 0.889)
					(end 4.445 -0.889)
					(stroke
						(width 0.254)
						(type default)
					)
					(fill
						(type none)
					)
				)
			)
			(symbol "R_330R_0402_1_1"
				(pin passive line
					(at 0 0 0)
					(length 0.635)
					(name "~"
						(effects
							(font
								(size 1.27 1.27)
							)
						)
					)
					(number "1"
						(effects
							(font
								(size 1.27 1.27)
							)
						)
					)
				)
				(pin passive line
					(at 5.08 0 180)
					(length 0.635)
					(name "~"
						(effects
							(font
								(size 1.27 1.27)
							)
						)
					)
					(number "2"
						(effects
							(font
								(size 1.27 1.27)
							)
						)
					)
				)
			)
		)
	(symbol "antmicroResistors0402:R_3k01_0402"
			(pin_numbers hide)
			(pin_names hide)
			(exclude_from_sim no)
			(in_bom yes)
			(on_board yes)
			(property "Reference" "R"
				(at 20.32 -5.08 0)
				(effects
					(font
						(size 1.27 1.27)
						(thickness 0.15)
					)
					(justify left bottom)
				)
			)
			(property "Value" "R_3k01_0402"
				(at 20.32 -12.7 0)
				(effects
					(font
						(size 1.27 1.27)
						(thickness 0.15)
					)
					(justify left bottom)
					(hide yes)
				)
			)
			(property "Footprint" "antmicro-footprints:R_0402_1005Metric"
				(at 20.32 -15.24 0)
				(effects
					(font
						(size 1.27 1.27)
						(thickness 0.15)
					)
					(justify left bottom)
					(hide yes)
				)
			)
			(property "Datasheet" "https://www.bourns.com/docs/product-datasheets/cr.pdf"
				(at 20.32 -17.78 0)
				(effects
					(font
						(size 1.27 1.27)
						(thickness 0.15)
					)
					(justify left bottom)
					(hide yes)
				)
			)
			(property "Description" "SMD Chip Resistor, 3.01 kohm, ± 1%, 62.5 mW, 0402 [1005 Metric], Thick Film, General Purpose"
				(at 0 0 0)
				(effects
					(font
						(size 1.27 1.27)
					)
					(hide yes)
				)
			)
			(property "MPN" "CR0402-FX-3011GLF"
				(at 20.32 -20.32 0)
				(effects
					(font
						(size 1.27 1.27)
						(thickness 0.15)
					)
					(justify left bottom)
					(hide yes)
				)
			)
			(property "Manufacturer" "Bourns"
				(at 20.32 -22.86 0)
				(effects
					(font
						(size 1.27 1.27)
						(thickness 0.15)
					)
					(justify left bottom)
					(hide yes)
				)
			)
			(property "License" "Apache-2.0"
				(at 20.32 -25.4 0)
				(effects
					(font
						(size 1.27 1.27)
						(thickness 0.15)
					)
					(justify left bottom)
					(hide yes)
				)
			)
			(property "Author" "Antmicro"
				(at 20.32 -27.94 0)
				(effects
					(font
						(size 1.27 1.27)
						(thickness 0.15)
					)
					(justify left bottom)
					(hide yes)
				)
			)
			(property "Val" "3k01"
				(at 20.32 -7.62 0)
				(effects
					(font
						(size 1.27 1.27)
						(thickness 0.15)
					)
					(justify left bottom)
				)
			)
			(property "Tolerance" "1%"
				(at 20.32 -10.16 0)
				(effects
					(font
						(size 1.27 1.27)
					)
					(justify left bottom)
					(hide yes)
				)
			)
			(property "ki_keywords" "0402, SMT, RESISTOR, PASSIVE"
				(at 0 0 0)
				(effects
					(font
						(size 1.27 1.27)
					)
					(hide yes)
				)
			)
			(symbol "R_3k01_0402_0_1"
				(rectangle
					(start 0.635 0.889)
					(end 4.445 -0.889)
					(stroke
						(width 0.254)
						(type default)
					)
					(fill
						(type none)
					)
				)
			)
			(symbol "R_3k01_0402_1_1"
				(pin passive line
					(at 0 0 0)
					(length 0.635)
					(name "~"
						(effects
							(font
								(size 1.27 1.27)
							)
						)
					)
					(number "1"
						(effects
							(font
								(size 1.27 1.27)
							)
						)
					)
				)
				(pin passive line
					(at 5.08 0 180)
					(length 0.635)
					(name "~"
						(effects
							(font
								(size 1.27 1.27)
							)
						)
					)
					(number "2"
						(effects
							(font
								(size 1.27 1.27)
							)
						)
					)
				)
			)
		)
	(symbol "antmicroResistors0402:R_3k3_0402"
			(pin_numbers hide)
			(pin_names hide)
			(exclude_from_sim no)
			(in_bom yes)
			(on_board yes)
			(property "Reference" "R"
				(at 20.32 -5.08 0)
				(effects
					(font
						(size 1.27 1.27)
						(thickness 0.15)
					)
					(justify left bottom)
				)
			)
			(property "Value" "R_3k3_0402"
				(at 20.32 -12.7 0)
				(effects
					(font
						(size 1.27 1.27)
						(thickness 0.15)
					)
					(justify left bottom)
					(hide yes)
				)
			)
			(property "Footprint" "antmicro-footprints:R_0402_1005Metric"
				(at 20.32 -15.24 0)
				(effects
					(font
						(size 1.27 1.27)
						(thickness 0.15)
					)
					(justify left bottom)
					(hide yes)
				)
			)
			(property "Datasheet" "https://www.bourns.com/docs/product-datasheets/cr.pdf"
				(at 20.32 -17.78 0)
				(effects
					(font
						(size 1.27 1.27)
						(thickness 0.15)
					)
					(justify left bottom)
					(hide yes)
				)
			)
			(property "Description" "SMD Chip Resistor, 3.3 kohm, ± 1%, 63 mW, 0402 [1005 Metric], Thick Film, General Purpose"
				(at 0 0 0)
				(effects
					(font
						(size 1.27 1.27)
					)
					(hide yes)
				)
			)
			(property "MPN" "CR0402-FX-3301GLF"
				(at 20.32 -20.32 0)
				(effects
					(font
						(size 1.27 1.27)
						(thickness 0.15)
					)
					(justify left bottom)
					(hide yes)
				)
			)
			(property "Manufacturer" "Bourns"
				(at 20.32 -22.86 0)
				(effects
					(font
						(size 1.27 1.27)
						(thickness 0.15)
					)
					(justify left bottom)
					(hide yes)
				)
			)
			(property "License" "Apache-2.0"
				(at 20.32 -25.4 0)
				(effects
					(font
						(size 1.27 1.27)
						(thickness 0.15)
					)
					(justify left bottom)
					(hide yes)
				)
			)
			(property "Author" "Antmicro"
				(at 20.32 -27.94 0)
				(effects
					(font
						(size 1.27 1.27)
						(thickness 0.15)
					)
					(justify left bottom)
					(hide yes)
				)
			)
			(property "Val" "3k3"
				(at 20.32 -7.62 0)
				(effects
					(font
						(size 1.27 1.27)
						(thickness 0.15)
					)
					(justify left bottom)
				)
			)
			(property "Tolerance" "1%"
				(at 20.32 -10.16 0)
				(effects
					(font
						(size 1.27 1.27)
					)
					(justify left bottom)
					(hide yes)
				)
			)
			(property "ki_keywords" "0402, SMT, RESISTOR, PASSIVE"
				(at 0 0 0)
				(effects
					(font
						(size 1.27 1.27)
					)
					(hide yes)
				)
			)
			(symbol "R_3k3_0402_0_1"
				(rectangle
					(start 0.635 0.889)
					(end 4.445 -0.889)
					(stroke
						(width 0.254)
						(type default)
					)
					(fill
						(type none)
					)
				)
			)
			(symbol "R_3k3_0402_1_1"
				(pin passive line
					(at 0 0 0)
					(length 0.635)
					(name "~"
						(effects
							(font
								(size 1.27 1.27)
							)
						)
					)
					(number "1"
						(effects
							(font
								(size 1.27 1.27)
							)
						)
					)
				)
				(pin passive line
					(at 5.08 0 180)
					(length 0.635)
					(name "~"
						(effects
							(font
								(size 1.27 1.27)
							)
						)
					)
					(number "2"
						(effects
							(font
								(size 1.27 1.27)
							)
						)
					)
				)
			)
		)
	(symbol "antmicroResistors0402:R_40k2_0402"
			(pin_numbers hide)
			(pin_names hide)
			(exclude_from_sim no)
			(in_bom yes)
			(on_board yes)
			(property "Reference" "R"
				(at 20.32 -5.08 0)
				(effects
					(font
						(size 1.27 1.27)
						(thickness 0.15)
					)
					(justify left bottom)
				)
			)
			(property "Value" "R_40k2_0402"
				(at 20.32 -12.7 0)
				(effects
					(font
						(size 1.27 1.27)
						(thickness 0.15)
					)
					(justify left bottom)
					(hide yes)
				)
			)
			(property "Footprint" "antmicro-footprints:R_0402_1005Metric"
				(at 20.32 -15.24 0)
				(effects
					(font
						(size 1.27 1.27)
						(thickness 0.15)
					)
					(justify left bottom)
					(hide yes)
				)
			)
			(property "Datasheet" "https://www.bourns.com/docs/product-datasheets/cr.pdf"
				(at 20.32 -17.78 0)
				(effects
					(font
						(size 1.27 1.27)
						(thickness 0.15)
					)
					(justify left bottom)
					(hide yes)
				)
			)
			(property "Description" "SMD Chip Resistor, 40.2 kohm, ± 1%, 63 mW, 0402 [1005 Metric], Thick Film, General Purpose"
				(at 0 0 0)
				(effects
					(font
						(size 1.27 1.27)
					)
					(hide yes)
				)
			)
			(property "MPN" "CR0402-FX-4022GLF"
				(at 20.32 -20.32 0)
				(effects
					(font
						(size 1.27 1.27)
						(thickness 0.15)
					)
					(justify left bottom)
					(hide yes)
				)
			)
			(property "Manufacturer" "Bourns"
				(at 20.32 -22.86 0)
				(effects
					(font
						(size 1.27 1.27)
						(thickness 0.15)
					)
					(justify left bottom)
					(hide yes)
				)
			)
			(property "License" "Apache-2.0"
				(at 20.32 -25.4 0)
				(effects
					(font
						(size 1.27 1.27)
						(thickness 0.15)
					)
					(justify left bottom)
					(hide yes)
				)
			)
			(property "Author" "Antmicro"
				(at 20.32 -27.94 0)
				(effects
					(font
						(size 1.27 1.27)
						(thickness 0.15)
					)
					(justify left bottom)
					(hide yes)
				)
			)
			(property "Val" "40k2"
				(at 20.32 -7.62 0)
				(effects
					(font
						(size 1.27 1.27)
						(thickness 0.15)
					)
					(justify left bottom)
				)
			)
			(property "Tolerance" "1%"
				(at 20.32 -10.16 0)
				(effects
					(font
						(size 1.27 1.27)
					)
					(justify left bottom)
					(hide yes)
				)
			)
			(property "ki_keywords" "0402, SMT, RESISTOR, PASSIVE"
				(at 0 0 0)
				(effects
					(font
						(size 1.27 1.27)
					)
					(hide yes)
				)
			)
			(symbol "R_40k2_0402_0_1"
				(rectangle
					(start 0.635 0.889)
					(end 4.445 -0.889)
					(stroke
						(width 0.254)
						(type default)
					)
					(fill
						(type none)
					)
				)
			)
			(symbol "R_40k2_0402_1_1"
				(pin passive line
					(at 0 0 0)
					(length 0.635)
					(name "~"
						(effects
							(font
								(size 1.27 1.27)
							)
						)
					)
					(number "1"
						(effects
							(font
								(size 1.27 1.27)
							)
						)
					)
				)
				(pin passive line
					(at 5.08 0 180)
					(length 0.635)
					(name "~"
						(effects
							(font
								(size 1.27 1.27)
							)
						)
					)
					(number "2"
						(effects
							(font
								(size 1.27 1.27)
							)
						)
					)
				)
			)
		)
	(symbol "antmicroResistors0402:R_47k_0402"
			(pin_numbers hide)
			(pin_names hide)
			(exclude_from_sim no)
			(in_bom yes)
			(on_board yes)
			(property "Reference" "R"
				(at 20.32 -5.08 0)
				(effects
					(font
						(size 1.27 1.27)
						(thickness 0.15)
					)
					(justify left bottom)
				)
			)
			(property "Value" "R_47k_0402"
				(at 20.32 -12.7 0)
				(effects
					(font
						(size 1.27 1.27)
						(thickness 0.15)
					)
					(justify left bottom)
					(hide yes)
				)
			)
			(property "Footprint" "antmicro-footprints:R_0402_1005Metric"
				(at 20.32 -15.24 0)
				(effects
					(font
						(size 1.27 1.27)
						(thickness 0.15)
					)
					(justify left bottom)
					(hide yes)
				)
			)
			(property "Datasheet" "https://www.bourns.com/docs/product-datasheets/cr.pdf"
				(at 20.32 -17.78 0)
				(effects
					(font
						(size 1.27 1.27)
						(thickness 0.15)
					)
					(justify left bottom)
					(hide yes)
				)
			)
			(property "Description" "SMD Chip Resistor, 47 kohm, ± 1%, 62.5 mW, 0402 [1005 Metric], Thick Film, General Purpose"
				(at 0 0 0)
				(effects
					(font
						(size 1.27 1.27)
					)
					(hide yes)
				)
			)
			(property "MPN" "CR0402-FX-4702GLF"
				(at 20.32 -20.32 0)
				(effects
					(font
						(size 1.27 1.27)
						(thickness 0.15)
					)
					(justify left bottom)
					(hide yes)
				)
			)
			(property "Manufacturer" "Bourns"
				(at 20.32 -22.86 0)
				(effects
					(font
						(size 1.27 1.27)
						(thickness 0.15)
					)
					(justify left bottom)
					(hide yes)
				)
			)
			(property "License" "Apache-2.0"
				(at 20.32 -25.4 0)
				(effects
					(font
						(size 1.27 1.27)
						(thickness 0.15)
					)
					(justify left bottom)
					(hide yes)
				)
			)
			(property "Author" "Antmicro"
				(at 20.32 -27.94 0)
				(effects
					(font
						(size 1.27 1.27)
						(thickness 0.15)
					)
					(justify left bottom)
					(hide yes)
				)
			)
			(property "Val" "47k"
				(at 20.32 -7.62 0)
				(effects
					(font
						(size 1.27 1.27)
						(thickness 0.15)
					)
					(justify left bottom)
				)
			)
			(property "Tolerance" "1%"
				(at 20.32 -10.16 0)
				(effects
					(font
						(size 1.27 1.27)
					)
					(justify left bottom)
					(hide yes)
				)
			)
			(property "ki_keywords" "0402, SMT, RESISTOR, PASSIVE"
				(at 0 0 0)
				(effects
					(font
						(size 1.27 1.27)
					)
					(hide yes)
				)
			)
			(symbol "R_47k_0402_0_1"
				(rectangle
					(start 0.635 0.889)
					(end 4.445 -0.889)
					(stroke
						(width 0.254)
						(type default)
					)
					(fill
						(type none)
					)
				)
			)
			(symbol "R_47k_0402_1_1"
				(pin passive line
					(at 0 0 0)
					(length 0.635)
					(name "~"
						(effects
							(font
								(size 1.27 1.27)
							)
						)
					)
					(number "1"
						(effects
							(font
								(size 1.27 1.27)
							)
						)
					)
				)
				(pin passive line
					(at 5.08 0 180)
					(length 0.635)
					(name "~"
						(effects
							(font
								(size 1.27 1.27)
							)
						)
					)
					(number "2"
						(effects
							(font
								(size 1.27 1.27)
							)
						)
					)
				)
			)
		)
	(symbol "antmicroResistors0402:R_499R_0402"
			(pin_numbers hide)
			(pin_names hide)
			(exclude_from_sim no)
			(in_bom yes)
			(on_board yes)
			(property "Reference" "R"
				(at 20.32 -5.08 0)
				(effects
					(font
						(size 1.27 1.27)
						(thickness 0.15)
					)
					(justify left bottom)
				)
			)
			(property "Value" "R_499R_0402"
				(at 20.32 -12.7 0)
				(effects
					(font
						(size 1.27 1.27)
						(thickness 0.15)
					)
					(justify left bottom)
					(hide yes)
				)
			)
			(property "Footprint" "antmicro-footprints:R_0402_1005Metric"
				(at 20.32 -15.24 0)
				(effects
					(font
						(size 1.27 1.27)
						(thickness 0.15)
					)
					(justify left bottom)
					(hide yes)
				)
			)
			(property "Datasheet" "https://www.mouser.com/datasheet/2/54/cr-1858361.pdf"
				(at 20.32 -17.78 0)
				(effects
					(font
						(size 1.27 1.27)
						(thickness 0.15)
					)
					(justify left bottom)
					(hide yes)
				)
			)
			(property "Description" "SMD Chip Resistor, 499 ohm, ± 1%, 63 mW, 0402 [1005 Metric], Thick Film, General Purpose"
				(at 0 0 0)
				(effects
					(font
						(size 1.27 1.27)
					)
					(hide yes)
				)
			)
			(property "MPN" "CR0402-FX-4990GLF"
				(at 20.32 -20.32 0)
				(effects
					(font
						(size 1.27 1.27)
						(thickness 0.15)
					)
					(justify left bottom)
					(hide yes)
				)
			)
			(property "Manufacturer" "Bourns"
				(at 20.32 -22.86 0)
				(effects
					(font
						(size 1.27 1.27)
						(thickness 0.15)
					)
					(justify left bottom)
					(hide yes)
				)
			)
			(property "License" "Apache-2.0"
				(at 20.32 -25.4 0)
				(effects
					(font
						(size 1.27 1.27)
						(thickness 0.15)
					)
					(justify left bottom)
					(hide yes)
				)
			)
			(property "Author" "Antmicro"
				(at 20.32 -27.94 0)
				(effects
					(font
						(size 1.27 1.27)
						(thickness 0.15)
					)
					(justify left bottom)
					(hide yes)
				)
			)
			(property "Val" "499R"
				(at 20.32 -7.62 0)
				(effects
					(font
						(size 1.27 1.27)
						(thickness 0.15)
					)
					(justify left bottom)
				)
			)
			(property "Tolerance" "1%"
				(at 20.32 -10.16 0)
				(effects
					(font
						(size 1.27 1.27)
					)
					(justify left bottom)
					(hide yes)
				)
			)
			(property "ki_keywords" "0402, SMT, RESISTOR, PASSIVE"
				(at 0 0 0)
				(effects
					(font
						(size 1.27 1.27)
					)
					(hide yes)
				)
			)
			(symbol "R_499R_0402_0_1"
				(rectangle
					(start 0.635 0.889)
					(end 4.445 -0.889)
					(stroke
						(width 0.254)
						(type default)
					)
					(fill
						(type none)
					)
				)
			)
			(symbol "R_499R_0402_1_1"
				(pin passive line
					(at 0 0 0)
					(length 0.635)
					(name "~"
						(effects
							(font
								(size 1.27 1.27)
							)
						)
					)
					(number "1"
						(effects
							(font
								(size 1.27 1.27)
							)
						)
					)
				)
				(pin passive line
					(at 5.08 0 180)
					(length 0.635)
					(name "~"
						(effects
							(font
								(size 1.27 1.27)
							)
						)
					)
					(number "2"
						(effects
							(font
								(size 1.27 1.27)
							)
						)
					)
				)
			)
		)
	(symbol "antmicroResistors0402:R_4k75_0.5%_0402"
			(pin_numbers hide)
			(pin_names hide)
			(exclude_from_sim no)
			(in_bom yes)
			(on_board yes)
			(property "Reference" "R"
				(at 20.32 -5.08 0)
				(effects
					(font
						(size 1.27 1.27)
						(thickness 0.15)
					)
					(justify left bottom)
				)
			)
			(property "Value" "R_4k75_0.5%_0402"
				(at 20.32 -12.7 0)
				(effects
					(font
						(size 1.27 1.27)
						(thickness 0.15)
					)
					(justify left bottom)
					(hide yes)
				)
			)
			(property "Footprint" "antmicro-footprints:R_0402_1005Metric"
				(at 20.32 -15.24 0)
				(effects
					(font
						(size 1.27 1.27)
						(thickness 0.15)
					)
					(justify left bottom)
					(hide yes)
				)
			)
			(property "Datasheet" "https://industrial.panasonic.com/cdbs/www-data/pdf/RDQ0000/ast-ind-151033.pdf"
				(at 20.32 -17.78 0)
				(effects
					(font
						(size 1.27 1.27)
						(thickness 0.15)
					)
					(justify left bottom)
					(hide yes)
				)
			)
			(property "Description" "SMD Chip Resistor, 4.75 kohm, ± 0.5%, 100 mW, 0402 [1005 Metric], Thick Film, High Temperature"
				(at 0 0 0)
				(effects
					(font
						(size 1.27 1.27)
					)
					(hide yes)
				)
			)
			(property "MPN" "ERJ-H2RD4751X"
				(at 20.32 -20.32 0)
				(effects
					(font
						(size 1.27 1.27)
						(thickness 0.15)
					)
					(justify left bottom)
					(hide yes)
				)
			)
			(property "Manufacturer" "Panasonic"
				(at 20.32 -22.86 0)
				(effects
					(font
						(size 1.27 1.27)
						(thickness 0.15)
					)
					(justify left bottom)
					(hide yes)
				)
			)
			(property "License" "Apache-2.0"
				(at 20.32 -25.4 0)
				(effects
					(font
						(size 1.27 1.27)
						(thickness 0.15)
					)
					(justify left bottom)
					(hide yes)
				)
			)
			(property "Author" "Antmicro"
				(at 20.32 -27.94 0)
				(effects
					(font
						(size 1.27 1.27)
						(thickness 0.15)
					)
					(justify left bottom)
					(hide yes)
				)
			)
			(property "Val" "4k75"
				(at 20.32 -7.62 0)
				(effects
					(font
						(size 1.27 1.27)
						(thickness 0.15)
					)
					(justify left bottom)
				)
			)
			(property "Tolerance" "0.5%"
				(at 20.32 -10.16 0)
				(effects
					(font
						(size 1.27 1.27)
					)
					(justify left bottom)
					(hide yes)
				)
			)
			(property "ki_keywords" "0402, SMT, RESISTOR, PASSIVE"
				(at 0 0 0)
				(effects
					(font
						(size 1.27 1.27)
					)
					(hide yes)
				)
			)
			(symbol "R_4k75_0.5%_0402_0_1"
				(rectangle
					(start 0.635 0.889)
					(end 4.445 -0.889)
					(stroke
						(width 0.254)
						(type default)
					)
					(fill
						(type none)
					)
				)
			)
			(symbol "R_4k75_0.5%_0402_1_1"
				(pin passive line
					(at 0 0 0)
					(length 0.635)
					(name "~"
						(effects
							(font
								(size 1.27 1.27)
							)
						)
					)
					(number "1"
						(effects
							(font
								(size 1.27 1.27)
							)
						)
					)
				)
				(pin passive line
					(at 5.08 0 180)
					(length 0.635)
					(name "~"
						(effects
							(font
								(size 1.27 1.27)
							)
						)
					)
					(number "2"
						(effects
							(font
								(size 1.27 1.27)
							)
						)
					)
				)
			)
		)
	(symbol "antmicroResistors0402:R_4k7_0402"
			(pin_numbers hide)
			(pin_names hide)
			(exclude_from_sim no)
			(in_bom yes)
			(on_board yes)
			(property "Reference" "R"
				(at 20.32 -5.08 0)
				(effects
					(font
						(size 1.27 1.27)
						(thickness 0.15)
					)
					(justify left bottom)
				)
			)
			(property "Value" "R_4k7_0402"
				(at 20.32 -12.7 0)
				(effects
					(font
						(size 1.27 1.27)
						(thickness 0.15)
					)
					(justify left bottom)
					(hide yes)
				)
			)
			(property "Footprint" "antmicro-footprints:R_0402_1005Metric"
				(at 20.32 -15.24 0)
				(effects
					(font
						(size 1.27 1.27)
						(thickness 0.15)
					)
					(justify left bottom)
					(hide yes)
				)
			)
			(property "Datasheet" "https://www.bourns.com/docs/product-datasheets/cr.pdf"
				(at 20.32 -17.78 0)
				(effects
					(font
						(size 1.27 1.27)
						(thickness 0.15)
					)
					(justify left bottom)
					(hide yes)
				)
			)
			(property "Description" "SMD Chip Resistor, 4.7 kohm, ± 1%, 62.5 mW, 0402 [1005 Metric], Thick Film, General Purpose"
				(at 0 0 0)
				(effects
					(font
						(size 1.27 1.27)
					)
					(hide yes)
				)
			)
			(property "MPN" "CR0402-FX-4701GLF"
				(at 20.32 -20.32 0)
				(effects
					(font
						(size 1.27 1.27)
						(thickness 0.15)
					)
					(justify left bottom)
					(hide yes)
				)
			)
			(property "Manufacturer" "Bourns"
				(at 20.32 -22.86 0)
				(effects
					(font
						(size 1.27 1.27)
						(thickness 0.15)
					)
					(justify left bottom)
					(hide yes)
				)
			)
			(property "License" "Apache-2.0"
				(at 20.32 -25.4 0)
				(effects
					(font
						(size 1.27 1.27)
						(thickness 0.15)
					)
					(justify left bottom)
					(hide yes)
				)
			)
			(property "Author" "Antmicro"
				(at 20.32 -27.94 0)
				(effects
					(font
						(size 1.27 1.27)
						(thickness 0.15)
					)
					(justify left bottom)
					(hide yes)
				)
			)
			(property "Val" "4k7"
				(at 20.32 -7.62 0)
				(effects
					(font
						(size 1.27 1.27)
						(thickness 0.15)
					)
					(justify left bottom)
				)
			)
			(property "Tolerance" "1%"
				(at 20.32 -10.16 0)
				(effects
					(font
						(size 1.27 1.27)
					)
					(justify left bottom)
					(hide yes)
				)
			)
			(property "ki_keywords" "0402, SMT, RESISTOR, PASSIVE"
				(at 0 0 0)
				(effects
					(font
						(size 1.27 1.27)
					)
					(hide yes)
				)
			)
			(symbol "R_4k7_0402_0_1"
				(rectangle
					(start 0.635 0.889)
					(end 4.445 -0.889)
					(stroke
						(width 0.254)
						(type default)
					)
					(fill
						(type none)
					)
				)
			)
			(symbol "R_4k7_0402_1_1"
				(pin passive line
					(at 0 0 0)
					(length 0.635)
					(name "~"
						(effects
							(font
								(size 1.27 1.27)
							)
						)
					)
					(number "1"
						(effects
							(font
								(size 1.27 1.27)
							)
						)
					)
				)
				(pin passive line
					(at 5.08 0 180)
					(length 0.635)
					(name "~"
						(effects
							(font
								(size 1.27 1.27)
							)
						)
					)
					(number "2"
						(effects
							(font
								(size 1.27 1.27)
							)
						)
					)
				)
			)
		)
	(symbol "antmicroResistors0402:R_5k1_0402"
			(pin_numbers hide)
			(pin_names hide)
			(exclude_from_sim no)
			(in_bom yes)
			(on_board yes)
			(property "Reference" "R"
				(at 20.32 -5.08 0)
				(effects
					(font
						(size 1.27 1.27)
						(thickness 0.15)
					)
					(justify left bottom)
				)
			)
			(property "Value" "R_5k1_0402"
				(at 20.32 -12.7 0)
				(effects
					(font
						(size 1.27 1.27)
						(thickness 0.15)
					)
					(justify left bottom)
					(hide yes)
				)
			)
			(property "Footprint" "antmicro-footprints:R_0402_1005Metric"
				(at 20.32 -15.24 0)
				(effects
					(font
						(size 1.27 1.27)
						(thickness 0.15)
					)
					(justify left bottom)
					(hide yes)
				)
			)
			(property "Datasheet" "https://www.bourns.com/docs/product-datasheets/cr.pdf"
				(at 20.32 -17.78 0)
				(effects
					(font
						(size 1.27 1.27)
						(thickness 0.15)
					)
					(justify left bottom)
					(hide yes)
				)
			)
			(property "Description" "SMD Chip Resistor, 5.1 kohm, ± 1%, 63 mW, 0402 [1005 Metric], Thick Film, General Purpose"
				(at 0 0 0)
				(effects
					(font
						(size 1.27 1.27)
					)
					(hide yes)
				)
			)
			(property "MPN" "CR0402-FX-5101GLF"
				(at 20.32 -20.32 0)
				(effects
					(font
						(size 1.27 1.27)
						(thickness 0.15)
					)
					(justify left bottom)
					(hide yes)
				)
			)
			(property "Manufacturer" "Bourns"
				(at 20.32 -22.86 0)
				(effects
					(font
						(size 1.27 1.27)
						(thickness 0.15)
					)
					(justify left bottom)
					(hide yes)
				)
			)
			(property "License" "Apache-2.0"
				(at 20.32 -25.4 0)
				(effects
					(font
						(size 1.27 1.27)
						(thickness 0.15)
					)
					(justify left bottom)
					(hide yes)
				)
			)
			(property "Author" "Antmicro"
				(at 20.32 -27.94 0)
				(effects
					(font
						(size 1.27 1.27)
						(thickness 0.15)
					)
					(justify left bottom)
					(hide yes)
				)
			)
			(property "Val" "5k1"
				(at 20.32 -7.62 0)
				(effects
					(font
						(size 1.27 1.27)
						(thickness 0.15)
					)
					(justify left bottom)
				)
			)
			(property "Tolerance" "1%"
				(at 20.32 -10.16 0)
				(effects
					(font
						(size 1.27 1.27)
					)
					(justify left bottom)
					(hide yes)
				)
			)
			(property "ki_keywords" "0402, SMT, RESISTOR, PASSIVE"
				(at 0 0 0)
				(effects
					(font
						(size 1.27 1.27)
					)
					(hide yes)
				)
			)
			(symbol "R_5k1_0402_0_1"
				(rectangle
					(start 0.635 0.889)
					(end 4.445 -0.889)
					(stroke
						(width 0.254)
						(type default)
					)
					(fill
						(type none)
					)
				)
			)
			(symbol "R_5k1_0402_1_1"
				(pin passive line
					(at 0 0 0)
					(length 0.635)
					(name "~"
						(effects
							(font
								(size 1.27 1.27)
							)
						)
					)
					(number "1"
						(effects
							(font
								(size 1.27 1.27)
							)
						)
					)
				)
				(pin passive line
					(at 5.08 0 180)
					(length 0.635)
					(name "~"
						(effects
							(font
								(size 1.27 1.27)
							)
						)
					)
					(number "2"
						(effects
							(font
								(size 1.27 1.27)
							)
						)
					)
				)
			)
		)
	(symbol "antmicroResistors0402:R_68R_0402"
			(pin_numbers hide)
			(pin_names hide)
			(exclude_from_sim no)
			(in_bom yes)
			(on_board yes)
			(property "Reference" "R"
				(at 20.32 -5.08 0)
				(effects
					(font
						(size 1.27 1.27)
						(thickness 0.15)
					)
					(justify left bottom)
				)
			)
			(property "Value" "R_68R_0402"
				(at 20.32 -12.7 0)
				(effects
					(font
						(size 1.27 1.27)
						(thickness 0.15)
					)
					(justify left bottom)
					(hide yes)
				)
			)
			(property "Footprint" "antmicro-footprints:R_0402_1005Metric"
				(at 20.32 -15.24 0)
				(effects
					(font
						(size 1.27 1.27)
						(thickness 0.15)
					)
					(justify left bottom)
					(hide yes)
				)
			)
			(property "Datasheet" "https://www.bourns.com/docs/product-datasheets/cr.pdf"
				(at 20.32 -17.78 0)
				(effects
					(font
						(size 1.27 1.27)
						(thickness 0.15)
					)
					(justify left bottom)
					(hide yes)
				)
			)
			(property "Description" "SMD Chip Resistor, 68 ohm, ± 1%, 62.5 mW, 0402 [1005 Metric], Thick Film, Sulfur Resistant"
				(at 0 0 0)
				(effects
					(font
						(size 1.27 1.27)
					)
					(hide yes)
				)
			)
			(property "MPN" "CR0402-FX-68R0GLF"
				(at 20.32 -20.32 0)
				(effects
					(font
						(size 1.27 1.27)
						(thickness 0.15)
					)
					(justify left bottom)
					(hide yes)
				)
			)
			(property "Manufacturer" "Bourns"
				(at 20.32 -22.86 0)
				(effects
					(font
						(size 1.27 1.27)
						(thickness 0.15)
					)
					(justify left bottom)
					(hide yes)
				)
			)
			(property "License" "Apache-2.0"
				(at 20.32 -25.4 0)
				(effects
					(font
						(size 1.27 1.27)
						(thickness 0.15)
					)
					(justify left bottom)
					(hide yes)
				)
			)
			(property "Author" "Antmicro"
				(at 20.32 -27.94 0)
				(effects
					(font
						(size 1.27 1.27)
						(thickness 0.15)
					)
					(justify left bottom)
					(hide yes)
				)
			)
			(property "Val" "68R"
				(at 20.32 -7.62 0)
				(effects
					(font
						(size 1.27 1.27)
						(thickness 0.15)
					)
					(justify left bottom)
				)
			)
			(property "Tolerance" "1%"
				(at 20.32 -10.16 0)
				(effects
					(font
						(size 1.27 1.27)
					)
					(justify left bottom)
					(hide yes)
				)
			)
			(property "ki_keywords" "0402, SMT, RESISTOR, PASSIVE"
				(at 0 0 0)
				(effects
					(font
						(size 1.27 1.27)
					)
					(hide yes)
				)
			)
			(symbol "R_68R_0402_0_1"
				(rectangle
					(start 0.635 0.889)
					(end 4.445 -0.889)
					(stroke
						(width 0.254)
						(type default)
					)
					(fill
						(type none)
					)
				)
			)
			(symbol "R_68R_0402_1_1"
				(pin passive line
					(at 0 0 0)
					(length 0.635)
					(name "~"
						(effects
							(font
								(size 1.27 1.27)
							)
						)
					)
					(number "1"
						(effects
							(font
								(size 1.27 1.27)
							)
						)
					)
				)
				(pin passive line
					(at 5.08 0 180)
					(length 0.635)
					(name "~"
						(effects
							(font
								(size 1.27 1.27)
							)
						)
					)
					(number "2"
						(effects
							(font
								(size 1.27 1.27)
							)
						)
					)
				)
			)
		)
	(symbol "antmicroResistors0402:R_8k2_0402"
			(pin_numbers hide)
			(pin_names hide)
			(exclude_from_sim no)
			(in_bom yes)
			(on_board yes)
			(property "Reference" "R"
				(at 20.32 -5.08 0)
				(effects
					(font
						(size 1.27 1.27)
						(thickness 0.15)
					)
					(justify left bottom)
				)
			)
			(property "Value" "R_8k2_0402"
				(at 20.32 -12.7 0)
				(effects
					(font
						(size 1.27 1.27)
						(thickness 0.15)
					)
					(justify left bottom)
					(hide yes)
				)
			)
			(property "Footprint" "antmicro-footprints:R_0402_1005Metric"
				(at 20.32 -15.24 0)
				(effects
					(font
						(size 1.27 1.27)
						(thickness 0.15)
					)
					(justify left bottom)
					(hide yes)
				)
			)
			(property "Datasheet" "https://www.bourns.com/docs/product-datasheets/cr.pdf"
				(at 20.32 -17.78 0)
				(effects
					(font
						(size 1.27 1.27)
						(thickness 0.15)
					)
					(justify left bottom)
					(hide yes)
				)
			)
			(property "Description" "SMD Chip Resistor"
				(at 0 0 0)
				(effects
					(font
						(size 1.27 1.27)
					)
					(hide yes)
				)
			)
			(property "MPN" "CR0402-FX-8201GLF"
				(at 20.32 -20.32 0)
				(effects
					(font
						(size 1.27 1.27)
						(thickness 0.15)
					)
					(justify left bottom)
					(hide yes)
				)
			)
			(property "Manufacturer" "Bourns"
				(at 20.32 -22.86 0)
				(effects
					(font
						(size 1.27 1.27)
						(thickness 0.15)
					)
					(justify left bottom)
					(hide yes)
				)
			)
			(property "License" "Apache-2.0"
				(at 20.32 -25.4 0)
				(effects
					(font
						(size 1.27 1.27)
						(thickness 0.15)
					)
					(justify left bottom)
					(hide yes)
				)
			)
			(property "Author" "Antmicro"
				(at 20.32 -27.94 0)
				(effects
					(font
						(size 1.27 1.27)
						(thickness 0.15)
					)
					(justify left bottom)
					(hide yes)
				)
			)
			(property "Val" "8k2"
				(at 20.32 -7.62 0)
				(effects
					(font
						(size 1.27 1.27)
						(thickness 0.15)
					)
					(justify left bottom)
				)
			)
			(property "Tolerance" "1%"
				(at 20.32 -10.16 0)
				(effects
					(font
						(size 1.27 1.27)
					)
					(justify left bottom)
					(hide yes)
				)
			)
			(property "ki_keywords" "0402, SMT, RESISTOR, PASSIVE"
				(at 0 0 0)
				(effects
					(font
						(size 1.27 1.27)
					)
					(hide yes)
				)
			)
			(symbol "R_8k2_0402_0_1"
				(rectangle
					(start 0.635 0.889)
					(end 4.445 -0.889)
					(stroke
						(width 0.254)
						(type default)
					)
					(fill
						(type none)
					)
				)
			)
			(symbol "R_8k2_0402_1_1"
				(pin passive line
					(at 0 0 0)
					(length 0.635)
					(name "~"
						(effects
							(font
								(size 1.27 1.27)
							)
						)
					)
					(number "1"
						(effects
							(font
								(size 1.27 1.27)
							)
						)
					)
				)
				(pin passive line
					(at 5.08 0 180)
					(length 0.635)
					(name "~"
						(effects
							(font
								(size 1.27 1.27)
							)
						)
					)
					(number "2"
						(effects
							(font
								(size 1.27 1.27)
							)
						)
					)
				)
			)
		)
	(symbol "antmicroResistors0402:R_8k87_0402"
			(pin_numbers hide)
			(pin_names hide)
			(exclude_from_sim no)
			(in_bom yes)
			(on_board yes)
			(property "Reference" "R"
				(at 20.32 -5.08 0)
				(effects
					(font
						(size 1.27 1.27)
						(thickness 0.15)
					)
					(justify left bottom)
				)
			)
			(property "Value" "R_8k87_0402"
				(at 20.32 -12.7 0)
				(effects
					(font
						(size 1.27 1.27)
						(thickness 0.15)
					)
					(justify left bottom)
					(hide yes)
				)
			)
			(property "Footprint" "antmicro-footprints:R_0402_1005Metric"
				(at 20.32 -15.24 0)
				(effects
					(font
						(size 1.27 1.27)
						(thickness 0.15)
					)
					(justify left bottom)
					(hide yes)
				)
			)
			(property "Datasheet" "https://www.bourns.com/docs/product-datasheets/cr.pdf"
				(at 20.32 -17.78 0)
				(effects
					(font
						(size 1.27 1.27)
						(thickness 0.15)
					)
					(justify left bottom)
					(hide yes)
				)
			)
			(property "Description" "SMD Chip Resistor, 8.87 kohm, ± 1%, 100 mW, 0402 [1005 Metric], Thick Film, Precision"
				(at 0 0 0)
				(effects
					(font
						(size 1.27 1.27)
					)
					(hide yes)
				)
			)
			(property "MPN" "CR0402-FX-8871GLF"
				(at 20.32 -20.32 0)
				(effects
					(font
						(size 1.27 1.27)
						(thickness 0.15)
					)
					(justify left bottom)
					(hide yes)
				)
			)
			(property "Manufacturer" "Bourns"
				(at 20.32 -22.86 0)
				(effects
					(font
						(size 1.27 1.27)
						(thickness 0.15)
					)
					(justify left bottom)
					(hide yes)
				)
			)
			(property "License" "Apache-2.0"
				(at 20.32 -25.4 0)
				(effects
					(font
						(size 1.27 1.27)
						(thickness 0.15)
					)
					(justify left bottom)
					(hide yes)
				)
			)
			(property "Author" "Antmicro"
				(at 20.32 -27.94 0)
				(effects
					(font
						(size 1.27 1.27)
						(thickness 0.15)
					)
					(justify left bottom)
					(hide yes)
				)
			)
			(property "Val" "8k87"
				(at 20.32 -7.62 0)
				(effects
					(font
						(size 1.27 1.27)
						(thickness 0.15)
					)
					(justify left bottom)
				)
			)
			(property "Tolerance" "1%"
				(at 20.32 -10.16 0)
				(effects
					(font
						(size 1.27 1.27)
					)
					(justify left bottom)
					(hide yes)
				)
			)
			(property "ki_keywords" "0402, SMT, RESISTOR, PASSIVE"
				(at 0 0 0)
				(effects
					(font
						(size 1.27 1.27)
					)
					(hide yes)
				)
			)
			(symbol "R_8k87_0402_0_1"
				(rectangle
					(start 0.635 0.889)
					(end 4.445 -0.889)
					(stroke
						(width 0.254)
						(type default)
					)
					(fill
						(type none)
					)
				)
			)
			(symbol "R_8k87_0402_1_1"
				(pin passive line
					(at 0 0 0)
					(length 0.635)
					(name "~"
						(effects
							(font
								(size 1.27 1.27)
							)
						)
					)
					(number "1"
						(effects
							(font
								(size 1.27 1.27)
							)
						)
					)
				)
				(pin passive line
					(at 5.08 0 180)
					(length 0.635)
					(name "~"
						(effects
							(font
								(size 1.27 1.27)
							)
						)
					)
					(number "2"
						(effects
							(font
								(size 1.27 1.27)
							)
						)
					)
				)
			)
		)
	(symbol "antmicroResistors0603:R_0R_0603"
			(pin_numbers hide)
			(pin_names hide)
			(exclude_from_sim no)
			(in_bom yes)
			(on_board yes)
			(property "Reference" "R"
				(at 20.32 -5.08 0)
				(effects
					(font
						(size 1.27 1.27)
						(thickness 0.15)
					)
					(justify left bottom)
				)
			)
			(property "Value" "R_0R_0603"
				(at 20.32 -12.7 0)
				(effects
					(font
						(size 1.27 1.27)
						(thickness 0.15)
					)
					(justify left bottom)
					(hide yes)
				)
			)
			(property "Footprint" "antmicro-footprints:R_0603_1608Metric"
				(at 20.32 -15.24 0)
				(effects
					(font
						(size 1.27 1.27)
						(thickness 0.15)
					)
					(justify left bottom)
					(hide yes)
				)
			)
			(property "Datasheet" "https://www.bourns.com/docs/product-datasheets/cr.pdf?sfvrsn=574d41f6_14"
				(at 20.32 -17.78 0)
				(effects
					(font
						(size 1.27 1.27)
						(thickness 0.15)
					)
					(justify left bottom)
					(hide yes)
				)
			)
			(property "Description" "Zero Ohm Resistor, Jumper, 0603 [1608 Metric], Thick Film, 100 mW, 1 A, Surface Mount Device, CR"
				(at 0 0 0)
				(effects
					(font
						(size 1.27 1.27)
					)
					(hide yes)
				)
			)
			(property "MPN" "CR0603-J/-000ELF"
				(at 20.32 -20.32 0)
				(effects
					(font
						(size 1.27 1.27)
						(thickness 0.15)
					)
					(justify left bottom)
					(hide yes)
				)
			)
			(property "Manufacturer" "Bourns"
				(at 20.32 -22.86 0)
				(effects
					(font
						(size 1.27 1.27)
						(thickness 0.15)
					)
					(justify left bottom)
					(hide yes)
				)
			)
			(property "License" "Apache-2.0"
				(at 20.32 -25.4 0)
				(effects
					(font
						(size 1.27 1.27)
						(thickness 0.15)
					)
					(justify left bottom)
					(hide yes)
				)
			)
			(property "Author" "Antmicro"
				(at 20.32 -27.94 0)
				(effects
					(font
						(size 1.27 1.27)
						(thickness 0.15)
					)
					(justify left bottom)
					(hide yes)
				)
			)
			(property "Val" "0R"
				(at 20.32 -7.62 0)
				(effects
					(font
						(size 1.27 1.27)
						(thickness 0.15)
					)
					(justify left bottom)
				)
			)
			(property "Tolerance" "~"
				(at 20.32 -10.16 0)
				(effects
					(font
						(size 1.27 1.27)
					)
					(justify left bottom)
					(hide yes)
				)
			)
			(property "Current" "1A"
				(at 20.32 -30.48 0)
				(effects
					(font
						(size 1.27 1.27)
						(thickness 0.15)
					)
					(justify left bottom)
					(hide yes)
				)
			)
			(property "ki_keywords" "0603, SMT, RESISTOR, PASSIVE"
				(at 0 0 0)
				(effects
					(font
						(size 1.27 1.27)
					)
					(hide yes)
				)
			)
			(symbol "R_0R_0603_0_1"
				(rectangle
					(start 0.635 0.889)
					(end 4.445 -0.889)
					(stroke
						(width 0.254)
						(type default)
					)
					(fill
						(type none)
					)
				)
			)
			(symbol "R_0R_0603_1_1"
				(pin passive line
					(at 0 0 0)
					(length 0.635)
					(name "~"
						(effects
							(font
								(size 1.27 1.27)
							)
						)
					)
					(number "1"
						(effects
							(font
								(size 1.27 1.27)
							)
						)
					)
				)
				(pin passive line
					(at 5.08 0 180)
					(length 0.635)
					(name "~"
						(effects
							(font
								(size 1.27 1.27)
							)
						)
					)
					(number "2"
						(effects
							(font
								(size 1.27 1.27)
							)
						)
					)
				)
			)
		)
	(symbol "antmicroResistors0603:R_0R_22.4A_0603"
			(pin_numbers hide)
			(pin_names hide)
			(exclude_from_sim no)
			(in_bom yes)
			(on_board yes)
			(property "Reference" "R"
				(at 15.24 -2.54 0)
				(effects
					(font
						(size 1.27 1.27)
						(thickness 0.15)
					)
					(justify left bottom)
				)
			)
			(property "Value" "R_0R_22.4A_0603"
				(at 15.24 -5.08 0)
				(effects
					(font
						(size 1.27 1.27)
						(thickness 0.15)
					)
					(justify left bottom)
				)
			)
			(property "Footprint" "antmicro-footprints:R_0603_1608Metric"
				(at 15.24 -10.16 0)
				(effects
					(font
						(size 1.27 1.27)
						(thickness 0.15)
					)
					(justify left bottom)
					(hide yes)
				)
			)
			(property "Datasheet" "https://fscdn.rohm.com/en/products/databook/datasheet/passive/resistor/chip_resistor/pmr-jpw-e.pdf"
				(at 15.24 -12.7 0)
				(effects
					(font
						(size 1.27 1.27)
						(thickness 0.15)
					)
					(justify left bottom)
					(hide yes)
				)
			)
			(property "Description" "SMD Chip Resistor"
				(at 0 0 0)
				(effects
					(font
						(size 1.27 1.27)
					)
					(hide yes)
				)
			)
			(property "MPN" "PMR03EZPJ000"
				(at 15.24 -15.24 0)
				(effects
					(font
						(size 1.27 1.27)
						(thickness 0.15)
					)
					(justify left bottom)
					(hide yes)
				)
			)
			(property "Manufacturer" "ROHM Semiconductor"
				(at 15.24 -17.78 0)
				(effects
					(font
						(size 1.27 1.27)
						(thickness 0.15)
					)
					(justify left bottom)
					(hide yes)
				)
			)
			(property "Val" "0R"
				(at 15.24 -7.62 0)
				(effects
					(font
						(size 1.27 1.27)
						(thickness 0.15)
					)
					(justify left bottom)
				)
			)
			(property "Max. Curr." "22.4A"
				(at 15.24 -20.32 0)
				(effects
					(font
						(size 1.27 1.27)
						(thickness 0.15)
					)
					(justify left bottom)
				)
			)
			(property "Author" "Antmicro"
				(at 15.24 -22.86 0)
				(effects
					(font
						(size 1.27 1.27)
						(thickness 0.15)
					)
					(justify left bottom)
					(hide yes)
				)
			)
			(property "License" "Apache-2.0"
				(at 15.24 -25.4 0)
				(effects
					(font
						(size 1.27 1.27)
						(thickness 0.15)
					)
					(justify left bottom)
					(hide yes)
				)
			)
			(property "Tolerance" "template_tolerance"
				(at 20.32 -10.16 0)
				(effects
					(font
						(size 1.27 1.27)
					)
					(justify left bottom)
					(hide yes)
				)
			)
			(property "ki_keywords" "0603, SMT, RESISTOR, PASSIVE"
				(at 0 0 0)
				(effects
					(font
						(size 1.27 1.27)
					)
					(hide yes)
				)
			)
			(symbol "R_0R_22.4A_0603_0_1"
				(rectangle
					(start 0.635 0.889)
					(end 4.445 -0.889)
					(stroke
						(width 0.254)
						(type default)
					)
					(fill
						(type none)
					)
				)
			)
			(symbol "R_0R_22.4A_0603_1_1"
				(pin passive line
					(at 0 0 0)
					(length 0.635)
					(name "~"
						(effects
							(font
								(size 1.27 1.27)
							)
						)
					)
					(number "1"
						(effects
							(font
								(size 1.27 1.27)
							)
						)
					)
				)
				(pin passive line
					(at 5.08 0 180)
					(length 0.635)
					(name "~"
						(effects
							(font
								(size 1.27 1.27)
							)
						)
					)
					(number "2"
						(effects
							(font
								(size 1.27 1.27)
							)
						)
					)
				)
			)
		)
	(symbol "antmicroResistorsmisc:R_0R02_1206"
			(pin_numbers hide)
			(pin_names hide)
			(exclude_from_sim no)
			(in_bom yes)
			(on_board yes)
			(property "Reference" "R"
				(at 20.32 -5.08 0)
				(effects
					(font
						(size 1.27 1.27)
						(thickness 0.15)
					)
					(justify left bottom)
				)
			)
			(property "Value" "R_0R02_1206"
				(at 20.32 -12.7 0)
				(effects
					(font
						(size 1.27 1.27)
						(thickness 0.15)
					)
					(justify left bottom)
					(hide yes)
				)
			)
			(property "Footprint" "antmicro-footprints:R_1206_3216Metric"
				(at 20.32 -15.24 0)
				(effects
					(font
						(size 1.27 1.27)
						(thickness 0.15)
					)
					(justify left bottom)
					(hide yes)
				)
			)
			(property "Datasheet" "https://www.mouser.com/datasheet/2/427/wslp-1763037.pdf"
				(at 20.32 -17.78 0)
				(effects
					(font
						(size 1.27 1.27)
						(thickness 0.15)
					)
					(justify left bottom)
					(hide yes)
				)
			)
			(property "Description" "Wirewound resistor, 0.02 ohm, 1W, ±1%"
				(at 0 0 0)
				(effects
					(font
						(size 1.27 1.27)
					)
					(hide yes)
				)
			)
			(property "MPN" "WSLP1206R0200FEA"
				(at 20.32 -20.32 0)
				(effects
					(font
						(size 1.27 1.27)
						(thickness 0.15)
					)
					(justify left bottom)
					(hide yes)
				)
			)
			(property "Manufacturer" "Vishay"
				(at 20.32 -22.86 0)
				(effects
					(font
						(size 1.27 1.27)
						(thickness 0.15)
					)
					(justify left bottom)
					(hide yes)
				)
			)
			(property "License" "Apache-2.0"
				(at 20.32 -25.4 0)
				(effects
					(font
						(size 1.27 1.27)
						(thickness 0.15)
					)
					(justify left bottom)
					(hide yes)
				)
			)
			(property "Author" "Antmicro"
				(at 20.32 -27.94 0)
				(effects
					(font
						(size 1.27 1.27)
						(thickness 0.15)
					)
					(justify left bottom)
					(hide yes)
				)
			)
			(property "Val" "0R02"
				(at 20.32 -7.62 0)
				(effects
					(font
						(size 1.27 1.27)
						(thickness 0.15)
					)
					(justify left bottom)
				)
			)
			(property "Tolerance" "1%"
				(at 20.32 -10.16 0)
				(effects
					(font
						(size 1.27 1.27)
					)
					(justify left bottom)
					(hide yes)
				)
			)
			(property "ki_keywords" "1206, SMT, RESISTOR, PASSIVE"
				(at 0 0 0)
				(effects
					(font
						(size 1.27 1.27)
					)
					(hide yes)
				)
			)
			(symbol "R_0R02_1206_0_1"
				(rectangle
					(start 0.635 0.889)
					(end 4.445 -0.889)
					(stroke
						(width 0.254)
						(type default)
					)
					(fill
						(type none)
					)
				)
			)
			(symbol "R_0R02_1206_1_1"
				(pin passive line
					(at 0 0 0)
					(length 0.635)
					(name "~"
						(effects
							(font
								(size 1.27 1.27)
							)
						)
					)
					(number "1"
						(effects
							(font
								(size 1.27 1.27)
							)
						)
					)
				)
				(pin passive line
					(at 5.08 0 180)
					(length 0.635)
					(name "~"
						(effects
							(font
								(size 1.27 1.27)
							)
						)
					)
					(number "2"
						(effects
							(font
								(size 1.27 1.27)
							)
						)
					)
				)
			)
		)
	(symbol "antmicroResonators:Resonator_25MHz_ABM8G"
			(pin_names hide)
			(exclude_from_sim no)
			(in_bom yes)
			(on_board yes)
			(property "Reference" "Y"
				(at 15.24 -5.08 0)
				(effects
					(font
						(size 1.27 1.27)
						(thickness 0.15)
					)
					(justify left bottom)
				)
			)
			(property "Value" "Resonator_25MHz_ABM8G"
				(at 15.24 -12.7 0)
				(effects
					(font
						(size 1.27 1.27)
						(thickness 0.15)
					)
					(justify left bottom)
					(hide yes)
				)
			)
			(property "Footprint" "antmicro-footprints:Resonator_SMD_Abracon_ABM8G_3.2x2.5mm"
				(at 15.24 -15.24 0)
				(effects
					(font
						(size 1.27 1.27)
						(thickness 0.15)
					)
					(justify left bottom)
					(hide yes)
				)
			)
			(property "Datasheet" "https://abracon.com/Resonators/ABM8G.pdf"
				(at 15.24 -17.78 0)
				(effects
					(font
						(size 1.27 1.27)
						(thickness 0.15)
					)
					(justify left bottom)
					(hide yes)
				)
			)
			(property "Description" "Crystal, 25 MHz, SMD, 3.2mm x 2.5mm, 30 ppm, 18 pF, 20 ppm, ABM8G"
				(at 0 0 0)
				(effects
					(font
						(size 1.27 1.27)
					)
					(hide yes)
				)
			)
			(property "MPN" "ABM8G-25.000MHZ-18-D2Y-T3"
				(at 15.24 -7.62 0)
				(effects
					(font
						(size 1.27 1.27)
						(thickness 0.15)
					)
					(justify left bottom)
				)
			)
			(property "Manufacturer" "Abracon"
				(at 15.24 -20.32 0)
				(effects
					(font
						(size 1.27 1.27)
						(thickness 0.15)
					)
					(justify left bottom)
					(hide yes)
				)
			)
			(property "Author" "Antmicro"
				(at 15.24 -22.86 0)
				(effects
					(font
						(size 1.27 1.27)
						(thickness 0.15)
					)
					(justify left bottom)
					(hide yes)
				)
			)
			(property "License" "Apache-2.0"
				(at 15.24 -25.4 0)
				(effects
					(font
						(size 1.27 1.27)
						(thickness 0.15)
					)
					(justify left bottom)
					(hide yes)
				)
			)
			(property "Val" "25 MHz"
				(at 15.24 -10.16 0)
				(effects
					(font
						(size 1.27 1.27)
						(thickness 0.15)
					)
					(justify left bottom)
				)
			)
			(property "ki_keywords" "SMT, CERAMIC, OSCILLATOR"
				(at 0 0 0)
				(effects
					(font
						(size 1.27 1.27)
					)
					(hide yes)
				)
			)
			(symbol "Resonator_25MHz_ABM8G_1_1"
				(polyline
					(pts
						(xy 2.54 1.27) (xy 2.54 -1.27)
					)
					(stroke
						(width 0.254)
						(type default)
					)
					(fill
						(type background)
					)
				)
				(polyline
					(pts
						(xy 5.08 1.27) (xy 5.08 -1.27)
					)
					(stroke
						(width 0.254)
						(type default)
					)
					(fill
						(type background)
					)
				)
				(polyline
					(pts
						(xy 1.905 -1.905) (xy 1.905 -2.54) (xy 5.715 -2.54) (xy 5.715 -1.905)
					)
					(stroke
						(width 0.254)
						(type default)
					)
					(fill
						(type none)
					)
				)
				(polyline
					(pts
						(xy 1.905 1.905) (xy 1.905 2.54) (xy 5.715 2.54) (xy 5.715 1.905)
					)
					(stroke
						(width 0.254)
						(type default)
					)
					(fill
						(type none)
					)
				)
				(rectangle
					(start 3.175 1.905)
					(end 4.445 -1.905)
					(stroke
						(width 0.254)
						(type default)
					)
					(fill
						(type background)
					)
				)
				(pin passive line
					(at 0 0 0)
					(length 2.54)
					(name "~"
						(effects
							(font
								(size 1.27 1.27)
							)
						)
					)
					(number "1"
						(effects
							(font
								(size 1.27 1.27)
							)
						)
					)
				)
				(pin passive line
					(at 3.81 -5.08 90)
					(length 2.54)
					(name "SH"
						(effects
							(font
								(size 1.27 1.27)
							)
						)
					)
					(number "2"
						(effects
							(font
								(size 1.27 1.27)
							)
						)
					)
				)
				(pin passive line
					(at 7.62 0 180)
					(length 2.54)
					(name "~"
						(effects
							(font
								(size 1.27 1.27)
							)
						)
					)
					(number "3"
						(effects
							(font
								(size 1.27 1.27)
							)
						)
					)
				)
				(pin passive line
					(at 3.81 -5.08 90)
					(length 2.54) hide
					(name "SH"
						(effects
							(font
								(size 1.27 1.27)
							)
						)
					)
					(number "4"
						(effects
							(font
								(size 1.27 1.27)
							)
						)
					)
				)
			)
		)
	(symbol "antmicroShuntsJumpers:Net-Tie_P0.127mm"
			(pin_names hide)
			(exclude_from_sim no)
			(in_bom no)
			(on_board yes)
			(property "Reference" "TP"
				(at 21.59 -5.08 0)
				(effects
					(font
						(size 1.27 1.27)
						(thickness 0.15)
					)
					(justify left bottom)
				)
			)
			(property "Value" "Net-Tie_P0.127mm"
				(at 21.59 -7.62 0)
				(effects
					(font
						(size 1.27 1.27)
						(thickness 0.15)
					)
					(justify left bottom)
				)
			)
			(property "Footprint" "antmicro-footprints:NetTie-2_SMD_Pad0.127mm"
				(at 21.59 -12.7 0)
				(effects
					(font
						(size 1.27 1.27)
						(thickness 0.15)
					)
					(justify left bottom)
					(hide yes)
				)
			)
			(property "Datasheet" ""
				(at 21.59 -15.24 0)
				(effects
					(font
						(size 1.27 1.27)
						(thickness 0.15)
					)
					(justify left bottom)
					(hide yes)
				)
			)
			(property "Description" "Net tie, 2 pins"
				(at 0 0 0)
				(effects
					(font
						(size 1.27 1.27)
					)
					(hide yes)
				)
			)
			(property "MPN" ""
				(at 21.59 -10.16 0)
				(effects
					(font
						(size 1.27 1.27)
						(thickness 0.15)
					)
					(justify left bottom)
				)
			)
			(property "Manufacturer" ""
				(at 21.59 -17.78 0)
				(effects
					(font
						(size 1.27 1.27)
						(thickness 0.15)
					)
					(justify left bottom)
					(hide yes)
				)
			)
			(property "Author" "Antmicro"
				(at 21.59 -20.32 0)
				(effects
					(font
						(size 1.27 1.27)
						(thickness 0.15)
					)
					(justify left bottom)
					(hide yes)
				)
			)
			(property "License" "Apache-2.0"
				(at 21.59 -22.86 0)
				(effects
					(font
						(size 1.27 1.27)
						(thickness 0.15)
					)
					(justify left bottom)
					(hide yes)
				)
			)
			(property "ki_fp_filters" "Net*Tie*"
				(at 0 0 0)
				(effects
					(font
						(size 1.27 1.27)
					)
					(hide yes)
				)
			)
			(symbol "Net-Tie_P0.127mm_1_1"
				(polyline
					(pts
						(xy 2.54 0) (xy 3.81 0)
					)
					(stroke
						(width 0.254)
						(type default)
					)
					(fill
						(type none)
					)
				)
				(pin passive line
					(at 0 0 0)
					(length 2.54)
					(name "1"
						(effects
							(font
								(size 1.27 1.27)
							)
						)
					)
					(number "1"
						(effects
							(font
								(size 1.27 1.27)
							)
						)
					)
				)
				(pin passive line
					(at 6.35 0 180)
					(length 2.54)
					(name "2"
						(effects
							(font
								(size 1.27 1.27)
							)
						)
					)
					(number "2"
						(effects
							(font
								(size 1.27 1.27)
							)
						)
					)
				)
			)
		)
	(symbol "antmicroTestPoints:TP_0.75mm_SMD"
			(pin_names hide)
			(exclude_from_sim no)
			(in_bom no)
			(on_board yes)
			(property "Reference" "TP"
				(at 10.16 -1.27 0)
				(effects
					(font
						(size 1.27 1.27)
						(thickness 0.15)
					)
					(justify left bottom)
				)
			)
			(property "Value" "TP_0.75mm_SMD"
				(at 10.16 -3.81 0)
				(effects
					(font
						(size 1.27 1.27)
						(thickness 0.15)
					)
					(justify left bottom)
					(hide yes)
				)
			)
			(property "Footprint" "antmicro-footprints:TP_SMD_0.75mm"
				(at 10.16 -6.35 0)
				(effects
					(font
						(size 1.27 1.27)
						(thickness 0.15)
					)
					(justify left bottom)
					(hide yes)
				)
			)
			(property "Datasheet" ""
				(at 17.78 -12.7 0)
				(effects
					(font
						(size 1.27 1.27)
						(thickness 0.15)
					)
					(justify left bottom)
					(hide yes)
				)
			)
			(property "Description" "SMT test point"
				(at 0 0 0)
				(effects
					(font
						(size 1.27 1.27)
					)
					(hide yes)
				)
			)
			(property "MPN" ""
				(at 10.795 -11.43 0)
				(effects
					(font
						(size 1.27 1.27)
						(thickness 0.15)
					)
					(justify left bottom)
					(hide yes)
				)
			)
			(property "Manufacturer" ""
				(at 10.795 -6.35 0)
				(effects
					(font
						(size 1.27 1.27)
						(thickness 0.15)
					)
					(justify left bottom)
					(hide yes)
				)
			)
			(property "Author" "Antmicro"
				(at 10.16 -8.89 0)
				(effects
					(font
						(size 1.27 1.27)
						(thickness 0.15)
					)
					(justify left bottom)
					(hide yes)
				)
			)
			(property "License" "Apache-2.0"
				(at 10.16 -11.43 0)
				(effects
					(font
						(size 1.27 1.27)
						(thickness 0.15)
					)
					(justify left bottom)
					(hide yes)
				)
			)
			(property "ki_keywords" "TESTPOINT"
				(at 0 0 0)
				(effects
					(font
						(size 1.27 1.27)
					)
					(hide yes)
				)
			)
			(symbol "TP_0.75mm_SMD_1_1"
				(circle
					(center 3.175 0)
					(radius 0.635)
					(stroke
						(width 0.254)
						(type default)
					)
					(fill
						(type none)
					)
				)
				(pin passive line
					(at 0 0 0)
					(length 2.54)
					(name "1"
						(effects
							(font
								(size 1.27 1.27)
							)
						)
					)
					(number "1"
						(effects
							(font
								(size 1.27 1.27)
							)
						)
					)
				)
			)
		)
	(symbol "antmicroTestPoints:TP_1mm_SMD"
			(pin_names hide)
			(exclude_from_sim no)
			(in_bom no)
			(on_board yes)
			(property "Reference" "TP"
				(at 15.24 -5.08 0)
				(effects
					(font
						(size 1.27 1.27)
						(thickness 0.15)
					)
					(justify left bottom)
				)
			)
			(property "Value" "TP_1mm_SMD"
				(at 15.24 -7.62 0)
				(effects
					(font
						(size 1.27 1.27)
						(thickness 0.15)
					)
					(justify left bottom)
					(hide yes)
				)
			)
			(property "Footprint" "antmicro-footprints:TP_SMD_1mm"
				(at 15.24 -10.16 0)
				(effects
					(font
						(size 1.27 1.27)
						(thickness 0.15)
					)
					(justify left bottom)
					(hide yes)
				)
			)
			(property "Datasheet" ""
				(at 17.78 -12.7 0)
				(effects
					(font
						(size 1.27 1.27)
						(thickness 0.15)
					)
					(justify left bottom)
					(hide yes)
				)
			)
			(property "Description" "Test point 1mm SMD"
				(at 0 0 0)
				(effects
					(font
						(size 1.27 1.27)
					)
					(hide yes)
				)
			)
			(property "MPN" ""
				(at 0 0 0)
				(effects
					(font
						(size 1.27 1.27)
					)
					(hide yes)
				)
			)
			(property "Manufacturer" ""
				(at 0 0 0)
				(effects
					(font
						(size 1.27 1.27)
					)
					(hide yes)
				)
			)
			(property "Author" "Antmicro"
				(at 15.24 -15.24 0)
				(effects
					(font
						(size 1.27 1.27)
						(thickness 0.15)
					)
					(justify left bottom)
					(hide yes)
				)
			)
			(property "License" "Apache-2.0"
				(at 15.24 -17.78 0)
				(effects
					(font
						(size 1.27 1.27)
						(thickness 0.15)
					)
					(justify left bottom)
					(hide yes)
				)
			)
			(property "ki_keywords" "TESTPOINT"
				(at 0 0 0)
				(effects
					(font
						(size 1.27 1.27)
					)
					(hide yes)
				)
			)
			(symbol "TP_1mm_SMD_1_1"
				(circle
					(center 3.175 0)
					(radius 0.635)
					(stroke
						(width 0.254)
						(type default)
					)
					(fill
						(type none)
					)
				)
				(pin passive line
					(at 0 0 0)
					(length 2.54)
					(name "1"
						(effects
							(font
								(size 1.27 1.27)
							)
						)
					)
					(number "1"
						(effects
							(font
								(size 1.27 1.27)
							)
						)
					)
				)
			)
		)
	(symbol "antmicroTransistorsBipolarSingle:BC817-25W"
			(pin_names
				(offset 0) hide)
			(exclude_from_sim no)
			(in_bom yes)
			(on_board yes)
			(property "Reference" "Q"
				(at 22.86 0 0)
				(effects
					(font
						(size 1.27 1.27)
						(thickness 0.15)
					)
					(justify left bottom)
				)
			)
			(property "Value" "BC817-25W"
				(at 22.86 -2.54 0)
				(effects
					(font
						(size 1.27 1.27)
						(thickness 0.15)
					)
					(justify left bottom)
					(hide yes)
				)
			)
			(property "Footprint" "antmicro-footprints:SOT-323"
				(at 22.86 -5.08 0)
				(effects
					(font
						(size 1.27 1.27)
						(thickness 0.15)
					)
					(justify left bottom)
					(hide yes)
				)
			)
			(property "Datasheet" "https://assets.nexperia.com/documents/data-sheet/BC817W_SER.pdf"
				(at 22.86 -7.62 0)
				(effects
					(font
						(size 1.27 1.27)
						(thickness 0.15)
					)
					(justify left bottom)
					(hide yes)
				)
			)
			(property "Description" "Bipolar (BJT) Single Transistor, NPN, 45 V, 500 mA, 200 mW, SOT-323, Surface Mount"
				(at 0 0 0)
				(effects
					(font
						(size 1.27 1.27)
					)
					(hide yes)
				)
			)
			(property "MPN" "BC817-25W,115"
				(at 22.86 -10.16 0)
				(effects
					(font
						(size 1.27 1.27)
						(thickness 0.15)
					)
					(justify left bottom)
				)
			)
			(property "Manufacturer" "Nexperia"
				(at 22.86 -12.7 0)
				(effects
					(font
						(size 1.27 1.27)
						(thickness 0.15)
					)
					(justify left bottom)
					(hide yes)
				)
			)
			(property "Author" "Antmicro"
				(at 22.86 -15.24 0)
				(effects
					(font
						(size 1.27 1.27)
						(thickness 0.15)
					)
					(justify left bottom)
					(hide yes)
				)
			)
			(property "License" "Apache-2.0"
				(at 22.86 -17.78 0)
				(effects
					(font
						(size 1.27 1.27)
						(thickness 0.15)
					)
					(justify left bottom)
					(hide yes)
				)
			)
			(property "ki_keywords" "SMT, TRANSISTOR, SEMICONDUCTOR, BIPOLAR"
				(at 0 0 0)
				(effects
					(font
						(size 1.27 1.27)
					)
					(hide yes)
				)
			)
			(property "ki_fp_filters" "SOT?323*"
				(at 0 0 0)
				(effects
					(font
						(size 1.27 1.27)
					)
					(hide yes)
				)
			)
			(symbol "BC817-25W_0_1"
				(polyline
					(pts
						(xy 2.54 0) (xy 4.445 0)
					)
					(stroke
						(width 0)
						(type default)
					)
					(fill
						(type none)
					)
				)
				(polyline
					(pts
						(xy 4.445 0.635) (xy 6.35 2.54)
					)
					(stroke
						(width 0)
						(type default)
					)
					(fill
						(type none)
					)
				)
				(polyline
					(pts
						(xy 4.445 -0.635) (xy 6.35 -2.54) (xy 6.35 -2.54)
					)
					(stroke
						(width 0)
						(type default)
					)
					(fill
						(type none)
					)
				)
				(polyline
					(pts
						(xy 4.445 1.905) (xy 4.445 -1.905) (xy 4.445 -1.905)
					)
					(stroke
						(width 0.508)
						(type default)
					)
					(fill
						(type none)
					)
				)
				(polyline
					(pts
						(xy 5.08 -1.778) (xy 5.588 -1.27) (xy 6.096 -2.286) (xy 5.08 -1.778) (xy 5.08 -1.778)
					)
					(stroke
						(width 0)
						(type default)
					)
					(fill
						(type outline)
					)
				)
				(circle
					(center 5.08 0)
					(radius 2.8194)
					(stroke
						(width 0.254)
						(type default)
					)
					(fill
						(type none)
					)
				)
			)
			(symbol "BC817-25W_1_1"
				(pin input line
					(at 0 0 0)
					(length 2.54)
					(name "B"
						(effects
							(font
								(size 1.27 1.27)
							)
						)
					)
					(number "1"
						(effects
							(font
								(size 1.27 1.27)
							)
						)
					)
				)
				(pin passive line
					(at 6.35 -5.08 90)
					(length 2.54)
					(name "E"
						(effects
							(font
								(size 1.27 1.27)
							)
						)
					)
					(number "2"
						(effects
							(font
								(size 1.27 1.27)
							)
						)
					)
				)
				(pin passive line
					(at 6.35 5.08 270)
					(length 2.54)
					(name "C"
						(effects
							(font
								(size 1.27 1.27)
							)
						)
					)
					(number "3"
						(effects
							(font
								(size 1.27 1.27)
							)
						)
					)
				)
			)
		)
	(symbol "antmicroTransistorsFETsMOSFETsSingle:SI7613DN-T1-GE3"
			(pin_names
				(offset 0)
			)
			(exclude_from_sim no)
			(in_bom yes)
			(on_board yes)
			(property "Reference" "Q"
				(at 15.24 5.08 0)
				(effects
					(font
						(size 1.27 1.27)
						(thickness 0.15)
					)
					(justify left bottom)
				)
			)
			(property "Value" "SI7613DN-T1-GE3"
				(at 15.24 2.54 0)
				(effects
					(font
						(size 1.27 1.27)
						(thickness 0.15)
					)
					(justify left bottom)
					(hide yes)
				)
			)
			(property "Footprint" "antmicro-footprints:Vishay_PowerPAK_1212-8_Single"
				(at 15.24 1.27 0)
				(effects
					(font
						(size 1.27 1.27)
						(thickness 0.15)
					)
					(justify left bottom)
					(hide yes)
				)
			)
			(property "Datasheet" "https://www.vishay.com/docs/64809/si7613dn.pdf"
				(at 15.24 -1.27 0)
				(effects
					(font
						(size 1.27 1.27)
						(thickness 0.15)
					)
					(justify left bottom)
					(hide yes)
				)
			)
			(property "Description" "Power MOSFET, P Channel, 20 V, 35 A, 0.0072 ohm, PowerPAK 1212, Surface Mount"
				(at 0 0 0)
				(effects
					(font
						(size 1.27 1.27)
					)
					(hide yes)
				)
			)
			(property "MPN" "SI7613DN-T1-GE3"
				(at 15.24 -5.08 0)
				(effects
					(font
						(size 1.27 1.27)
						(thickness 0.15)
					)
					(justify left bottom)
				)
			)
			(property "Manufacturer" "Vishay"
				(at 15.24 -7.62 0)
				(effects
					(font
						(size 1.27 1.27)
						(thickness 0.15)
					)
					(justify left bottom)
					(hide yes)
				)
			)
			(property "Author" "Antmicro"
				(at 15.24 -10.16 0)
				(effects
					(font
						(size 1.27 1.27)
						(thickness 0.15)
					)
					(justify left bottom)
					(hide yes)
				)
			)
			(property "License" "Apache-2.0"
				(at 15.24 -12.7 0)
				(effects
					(font
						(size 1.27 1.27)
						(thickness 0.15)
					)
					(justify left bottom)
					(hide yes)
				)
			)
			(property "ki_keywords" "SMT, TRANSISTOR, SEMICONDUCTOR, MOSFET, PMOS"
				(at 0 0 0)
				(effects
					(font
						(size 1.27 1.27)
					)
					(hide yes)
				)
			)
			(symbol "SI7613DN-T1-GE3_1_1"
				(polyline
					(pts
						(xy 5.08 1.143) (xy 5.08 0.635)
					)
					(stroke
						(width 0.254)
						(type default)
					)
					(fill
						(type background)
					)
				)
				(polyline
					(pts
						(xy 5.08 1.143) (xy 5.08 1.651)
					)
					(stroke
						(width 0.254)
						(type default)
					)
					(fill
						(type background)
					)
				)
				(polyline
					(pts
						(xy 5.08 2.54) (xy 5.08 2.032)
					)
					(stroke
						(width 0.254)
						(type default)
					)
					(fill
						(type background)
					)
				)
				(polyline
					(pts
						(xy 5.08 2.54) (xy 5.08 3.048)
					)
					(stroke
						(width 0.254)
						(type default)
					)
					(fill
						(type background)
					)
				)
				(polyline
					(pts
						(xy 5.08 4.445) (xy 5.08 3.429)
					)
					(stroke
						(width 0.254)
						(type default)
					)
					(fill
						(type background)
					)
				)
				(polyline
					(pts
						(xy 7.62 1.143) (xy 5.08 1.143)
					)
					(stroke
						(width 0.254)
						(type default)
					)
					(fill
						(type background)
					)
				)
				(polyline
					(pts
						(xy 9.144 2.2352) (xy 8.128 2.2352)
					)
					(stroke
						(width 0.254)
						(type default)
					)
					(fill
						(type background)
					)
				)
				(polyline
					(pts
						(xy 2.54 0) (xy 4.572 0) (xy 4.572 3.937)
					)
					(stroke
						(width 0.254)
						(type default)
					)
					(fill
						(type none)
					)
				)
				(polyline
					(pts
						(xy 7.62 -1.27) (xy 7.62 2.54) (xy 5.08 2.54)
					)
					(stroke
						(width 0.254)
						(type default)
					)
					(fill
						(type none)
					)
				)
				(polyline
					(pts
						(xy 7.62 6.35) (xy 7.62 3.937) (xy 5.08 3.937)
					)
					(stroke
						(width 0.254)
						(type default)
					)
					(fill
						(type none)
					)
				)
				(polyline
					(pts
						(xy 7.239 2.54) (xy 6.477 3.048) (xy 6.477 2.032) (xy 7.239 2.54)
					)
					(stroke
						(width 0.254)
						(type default)
					)
					(fill
						(type outline)
					)
				)
				(polyline
					(pts
						(xy 8.636 2.286) (xy 8.128 3.048) (xy 9.144 3.048) (xy 8.636 2.286)
					)
					(stroke
						(width 0.254)
						(type default)
					)
					(fill
						(type outline)
					)
				)
				(polyline
					(pts
						(xy 7.493 0.635) (xy 8.636 0.635) (xy 8.636 3.937) (xy 8.636 4.445) (xy 7.493 4.445)
					)
					(stroke
						(width 0.254)
						(type default)
					)
					(fill
						(type background)
					)
				)
				(circle
					(center 6.35 2.54)
					(radius 3.302)
					(stroke
						(width 0.254)
						(type default)
					)
					(fill
						(type background)
					)
				)
				(circle
					(center 7.62 0.635)
					(radius 0.127)
					(stroke
						(width 0.254)
						(type default)
					)
					(fill
						(type background)
					)
				)
				(circle
					(center 7.62 1.143)
					(radius 0.127)
					(stroke
						(width 0.254)
						(type default)
					)
					(fill
						(type background)
					)
				)
				(circle
					(center 7.62 4.445)
					(radius 0.127)
					(stroke
						(width 0.254)
						(type default)
					)
					(fill
						(type background)
					)
				)
				(pin passive line
					(at 7.62 -3.81 90)
					(length 2.54)
					(name "S"
						(effects
							(font
								(size 1.27 1.27)
							)
						)
					)
					(number "1"
						(effects
							(font
								(size 1.27 1.27)
							)
						)
					)
				)
				(pin passive line
					(at 7.62 -3.81 90)
					(length 2.54) hide
					(name "S"
						(effects
							(font
								(size 1.27 1.27)
							)
						)
					)
					(number "2"
						(effects
							(font
								(size 1.27 1.27)
							)
						)
					)
				)
				(pin passive line
					(at 7.62 -3.81 90)
					(length 2.54) hide
					(name "S"
						(effects
							(font
								(size 1.27 1.27)
							)
						)
					)
					(number "3"
						(effects
							(font
								(size 1.27 1.27)
							)
						)
					)
				)
				(pin passive line
					(at 0 0 0)
					(length 2.54)
					(name "G"
						(effects
							(font
								(size 1.27 1.27)
							)
						)
					)
					(number "4"
						(effects
							(font
								(size 1.27 1.27)
							)
						)
					)
				)
				(pin passive line
					(at 7.62 8.89 270)
					(length 2.54)
					(name "D"
						(effects
							(font
								(size 1.27 1.27)
							)
						)
					)
					(number "5"
						(effects
							(font
								(size 1.27 1.27)
							)
						)
					)
				)
			)
		)
	(symbol "antmicroUSBConnectors:USB-C_JAE_DX07S024JJ2"
			(exclude_from_sim no)
			(in_bom yes)
			(on_board yes)
			(property "Reference" "J"
				(at 36.83 2.54 0)
				(effects
					(font
						(size 1.27 1.27)
						(thickness 0.15)
					)
					(justify left bottom)
				)
			)
			(property "Value" "USB-C_JAE_DX07S024JJ2"
				(at 36.83 0 0)
				(effects
					(font
						(size 1.27 1.27)
						(thickness 0.15)
					)
					(justify left bottom)
					(hide yes)
				)
			)
			(property "Footprint" "antmicro-footprints:USB-C_Receptacle_JAE_DX07S024JJ2"
				(at 36.83 -2.54 0)
				(effects
					(font
						(size 1.27 1.27)
						(thickness 0.15)
					)
					(justify left bottom)
					(hide yes)
				)
			)
			(property "Datasheet" "https://www.jae.com/en/connectors/series/detail/product/id=66508"
				(at 36.83 -5.08 0)
				(effects
					(font
						(size 1.27 1.27)
						(thickness 0.15)
					)
					(justify left bottom)
					(hide yes)
				)
			)
			(property "Description" "USB-C (USB TYPE-C) USB 3.2 Gen 2 (USB 3.1 Gen 2, Superspeed + (USB 3.1)) Receptacle Connector 24 Position Surface Mount, Right Angle"
				(at 0 0 0)
				(effects
					(font
						(size 1.27 1.27)
					)
					(hide yes)
				)
			)
			(property "MPN" "DX07S024JJ2"
				(at 36.83 -7.62 0)
				(effects
					(font
						(size 1.27 1.27)
						(thickness 0.15)
					)
					(justify left bottom)
				)
			)
			(property "Manufacturer" "JAE Electronics"
				(at 36.83 -10.16 0)
				(effects
					(font
						(size 1.27 1.27)
						(thickness 0.15)
					)
					(justify left bottom)
					(hide yes)
				)
			)
			(property "Author" "Antmicro"
				(at 36.83 -12.7 0)
				(effects
					(font
						(size 1.27 1.27)
						(thickness 0.15)
					)
					(justify left bottom)
					(hide yes)
				)
			)
			(property "License" "Apache-2.0"
				(at 36.83 -15.24 0)
				(effects
					(font
						(size 1.27 1.27)
						(thickness 0.15)
					)
					(justify left bottom)
					(hide yes)
				)
			)
			(property "ki_keywords" "USB, CONNECTOR, SMT, HORIZONTAL"
				(at 0 0 0)
				(effects
					(font
						(size 1.27 1.27)
					)
					(hide yes)
				)
			)
			(symbol "USB-C_JAE_DX07S024JJ2_1_1"
				(rectangle
					(start -22.86 -68.58)
					(end -3.81 2.54)
					(stroke
						(width 0.254)
						(type default)
					)
					(fill
						(type background)
					)
				)
				(circle
					(center -20.066 -33.274)
					(radius 0.284)
					(stroke
						(width 0.254)
						(type default)
					)
					(fill
						(type outline)
					)
				)
				(circle
					(center -19.177 -36.068)
					(radius 0.5236)
					(stroke
						(width 0.254)
						(type default)
					)
					(fill
						(type outline)
					)
				)
				(rectangle
					(start -18.669 -33.274)
					(end -17.907 -32.512)
					(stroke
						(width 0.254)
						(type default)
					)
					(fill
						(type outline)
					)
				)
				(arc
					(start -16.51 -36.83)
					(mid -14.605 -38.7267)
					(end -12.7 -36.83)
					(stroke
						(width 0.254)
						(type default)
					)
					(fill
						(type background)
					)
				)
				(arc
					(start -15.24 -36.83)
					(mid -14.605 -37.4623)
					(end -13.97 -36.83)
					(stroke
						(width 0.254)
						(type default)
					)
					(fill
						(type outline)
					)
				)
				(arc
					(start -15.24 -36.83)
					(mid -14.605 -37.4623)
					(end -13.97 -36.83)
					(stroke
						(width 0.254)
						(type default)
					)
					(fill
						(type background)
					)
				)
				(rectangle
					(start -15.24 -36.83)
					(end -13.97 -29.21)
					(stroke
						(width 0.254)
						(type default)
					)
					(fill
						(type outline)
					)
				)
				(arc
					(start -13.97 -29.21)
					(mid -14.605 -28.5777)
					(end -15.24 -29.21)
					(stroke
						(width 0.254)
						(type default)
					)
					(fill
						(type outline)
					)
				)
				(arc
					(start -13.97 -29.21)
					(mid -14.605 -28.5777)
					(end -15.24 -29.21)
					(stroke
						(width 0.254)
						(type default)
					)
					(fill
						(type background)
					)
				)
				(arc
					(start -12.7 -29.21)
					(mid -14.605 -27.3133)
					(end -16.51 -29.21)
					(stroke
						(width 0.254)
						(type default)
					)
					(fill
						(type background)
					)
				)
				(polyline
					(pts
						(xy -19.177 -35.941) (xy -19.177 -31.623)
					)
					(stroke
						(width 0.254)
						(type default)
					)
					(fill
						(type background)
					)
				)
				(polyline
					(pts
						(xy -16.51 -36.83) (xy -16.51 -29.21)
					)
					(stroke
						(width 0.254)
						(type default)
					)
					(fill
						(type background)
					)
				)
				(polyline
					(pts
						(xy -12.7 -29.21) (xy -12.7 -36.83)
					)
					(stroke
						(width 0.254)
						(type default)
					)
					(fill
						(type background)
					)
				)
				(polyline
					(pts
						(xy -19.177 -35.179) (xy -20.066 -34.29) (xy -20.066 -33.655)
					)
					(stroke
						(width 0.254)
						(type default)
					)
					(fill
						(type background)
					)
				)
				(polyline
					(pts
						(xy -19.177 -34.798) (xy -18.288 -33.909) (xy -18.288 -33.274)
					)
					(stroke
						(width 0.254)
						(type default)
					)
					(fill
						(type background)
					)
				)
				(polyline
					(pts
						(xy -19.812 -31.623) (xy -19.177 -30.48) (xy -18.542 -31.623) (xy -19.812 -31.623)
					)
					(stroke
						(width 0.254)
						(type default)
					)
					(fill
						(type outline)
					)
				)
				(pin power_in line
					(at 0 -63.5 180)
					(length 3.81)
					(name "GND"
						(effects
							(font
								(size 1.27 1.27)
							)
						)
					)
					(number "A1"
						(effects
							(font
								(size 1.27 1.27)
							)
						)
					)
				)
				(pin bidirectional line
					(at 0 -43.18 180)
					(length 3.81)
					(name "RX_{2}-"
						(effects
							(font
								(size 1.27 1.27)
							)
						)
					)
					(number "A10"
						(effects
							(font
								(size 1.27 1.27)
							)
						)
					)
				)
				(pin bidirectional line
					(at 0 -40.64 180)
					(length 3.81)
					(name "RX_{2}+"
						(effects
							(font
								(size 1.27 1.27)
							)
						)
					)
					(number "A11"
						(effects
							(font
								(size 1.27 1.27)
							)
						)
					)
				)
				(pin passive line
					(at 0 -63.5 180)
					(length 3.81) hide
					(name "GND"
						(effects
							(font
								(size 1.27 1.27)
							)
						)
					)
					(number "A12"
						(effects
							(font
								(size 1.27 1.27)
							)
						)
					)
				)
				(pin bidirectional line
					(at 0 -33.02 180)
					(length 3.81)
					(name "TX_{1}+"
						(effects
							(font
								(size 1.27 1.27)
							)
						)
					)
					(number "A2"
						(effects
							(font
								(size 1.27 1.27)
							)
						)
					)
				)
				(pin bidirectional line
					(at 0 -35.56 180)
					(length 3.81)
					(name "TX_{1}-"
						(effects
							(font
								(size 1.27 1.27)
							)
						)
					)
					(number "A3"
						(effects
							(font
								(size 1.27 1.27)
							)
						)
					)
				)
				(pin passive line
					(at 0 0 180)
					(length 3.81)
					(name "VBUS"
						(effects
							(font
								(size 1.27 1.27)
							)
						)
					)
					(number "A4"
						(effects
							(font
								(size 1.27 1.27)
							)
						)
					)
				)
				(pin bidirectional line
					(at 0 -5.08 180)
					(length 3.81)
					(name "CC_{1}"
						(effects
							(font
								(size 1.27 1.27)
							)
						)
					)
					(number "A5"
						(effects
							(font
								(size 1.27 1.27)
							)
						)
					)
				)
				(pin bidirectional line
					(at 0 -12.7 180)
					(length 3.81)
					(name "D_{A}+"
						(effects
							(font
								(size 1.27 1.27)
							)
						)
					)
					(number "A6"
						(effects
							(font
								(size 1.27 1.27)
							)
						)
					)
				)
				(pin bidirectional line
					(at 0 -15.24 180)
					(length 3.81)
					(name "D_{A}-"
						(effects
							(font
								(size 1.27 1.27)
							)
						)
					)
					(number "A7"
						(effects
							(font
								(size 1.27 1.27)
							)
						)
					)
				)
				(pin bidirectional line
					(at 0 -55.88 180)
					(length 3.81)
					(name "SBU_{1}"
						(effects
							(font
								(size 1.27 1.27)
							)
						)
					)
					(number "A8"
						(effects
							(font
								(size 1.27 1.27)
							)
						)
					)
				)
				(pin passive line
					(at 0 0 180)
					(length 3.81) hide
					(name "VBUS"
						(effects
							(font
								(size 1.27 1.27)
							)
						)
					)
					(number "A9"
						(effects
							(font
								(size 1.27 1.27)
							)
						)
					)
				)
				(pin passive line
					(at 0 -63.5 180)
					(length 3.81) hide
					(name "GND"
						(effects
							(font
								(size 1.27 1.27)
							)
						)
					)
					(number "B1"
						(effects
							(font
								(size 1.27 1.27)
							)
						)
					)
				)
				(pin bidirectional line
					(at 0 -27.94 180)
					(length 3.81)
					(name "RX_{1}-"
						(effects
							(font
								(size 1.27 1.27)
							)
						)
					)
					(number "B10"
						(effects
							(font
								(size 1.27 1.27)
							)
						)
					)
				)
				(pin bidirectional line
					(at 0 -25.4 180)
					(length 3.81)
					(name "RX_{1}+"
						(effects
							(font
								(size 1.27 1.27)
							)
						)
					)
					(number "B11"
						(effects
							(font
								(size 1.27 1.27)
							)
						)
					)
				)
				(pin passive line
					(at 0 -63.5 180)
					(length 3.81) hide
					(name "GND"
						(effects
							(font
								(size 1.27 1.27)
							)
						)
					)
					(number "B12"
						(effects
							(font
								(size 1.27 1.27)
							)
						)
					)
				)
				(pin bidirectional line
					(at 0 -48.26 180)
					(length 3.81)
					(name "TX_{2}+"
						(effects
							(font
								(size 1.27 1.27)
							)
						)
					)
					(number "B2"
						(effects
							(font
								(size 1.27 1.27)
							)
						)
					)
				)
				(pin bidirectional line
					(at 0 -50.8 180)
					(length 3.81)
					(name "TX_{2}-"
						(effects
							(font
								(size 1.27 1.27)
							)
						)
					)
					(number "B3"
						(effects
							(font
								(size 1.27 1.27)
							)
						)
					)
				)
				(pin passive line
					(at 0 0 180)
					(length 3.81) hide
					(name "VBUS"
						(effects
							(font
								(size 1.27 1.27)
							)
						)
					)
					(number "B4"
						(effects
							(font
								(size 1.27 1.27)
							)
						)
					)
				)
				(pin bidirectional line
					(at 0 -7.62 180)
					(length 3.81)
					(name "CC_{2}"
						(effects
							(font
								(size 1.27 1.27)
							)
						)
					)
					(number "B5"
						(effects
							(font
								(size 1.27 1.27)
							)
						)
					)
				)
				(pin bidirectional line
					(at 0 -17.78 180)
					(length 3.81)
					(name "D_{B}+"
						(effects
							(font
								(size 1.27 1.27)
							)
						)
					)
					(number "B6"
						(effects
							(font
								(size 1.27 1.27)
							)
						)
					)
				)
				(pin bidirectional line
					(at 0 -20.32 180)
					(length 3.81)
					(name "D_{B}-"
						(effects
							(font
								(size 1.27 1.27)
							)
						)
					)
					(number "B7"
						(effects
							(font
								(size 1.27 1.27)
							)
						)
					)
				)
				(pin bidirectional line
					(at 0 -58.42 180)
					(length 3.81)
					(name "SBU_{2}"
						(effects
							(font
								(size 1.27 1.27)
							)
						)
					)
					(number "B8"
						(effects
							(font
								(size 1.27 1.27)
							)
						)
					)
				)
				(pin passive line
					(at 0 0 180)
					(length 3.81) hide
					(name "VBUS"
						(effects
							(font
								(size 1.27 1.27)
							)
						)
					)
					(number "B9"
						(effects
							(font
								(size 1.27 1.27)
							)
						)
					)
				)
				(pin passive line
					(at 0 -66.04 180)
					(length 3.81)
					(name "SH"
						(effects
							(font
								(size 1.27 1.27)
							)
						)
					)
					(number "SH"
						(effects
							(font
								(size 1.27 1.27)
							)
						)
					)
				)
			)
		)
	(symbol "antmicroWire2BoardConnectors:JST_SH_1x2_SM02B-SRSS-TB-LF-SN"
			(exclude_from_sim no)
			(in_bom yes)
			(on_board yes)
			(property "Reference" "J"
				(at 26.67 -3.81 0)
				(effects
					(font
						(size 1.27 1.27)
						(thickness 0.15)
					)
					(justify left bottom)
				)
			)
			(property "Value" "JST_SH_1x2_SM02B-SRSS-TB-LF-SN"
				(at 26.67 -6.35 0)
				(effects
					(font
						(size 1.27 1.27)
						(thickness 0.15)
					)
					(justify left bottom)
					(hide yes)
				)
			)
			(property "Footprint" "antmicro-footprints:Conn_JST_SH_1x2_SM02B-SRSS-TB-LF-SN"
				(at 26.67 -8.89 0)
				(effects
					(font
						(size 1.27 1.27)
						(thickness 0.15)
					)
					(justify left bottom)
					(hide yes)
				)
			)
			(property "Datasheet" "https://www.jst-mfg.com/product/pdf/eng/eSH.pdf"
				(at 26.67 -11.43 0)
				(effects
					(font
						(size 1.27 1.27)
						(thickness 0.15)
					)
					(justify left bottom)
					(hide yes)
				)
			)
			(property "Description" "Rectangular connector, header"
				(at 0 0 0)
				(effects
					(font
						(size 1.27 1.27)
					)
					(hide yes)
				)
			)
			(property "MPN" "SM02B-SRSS-TB(LF)(SN)"
				(at 26.67 -13.97 0)
				(effects
					(font
						(size 1.27 1.27)
						(thickness 0.15)
					)
					(justify left bottom)
				)
			)
			(property "Manufacturer" "JST Automotive Connectors"
				(at 26.67 -16.51 0)
				(effects
					(font
						(size 1.27 1.27)
						(thickness 0.15)
					)
					(justify left bottom)
					(hide yes)
				)
			)
			(property "Author" "Antmicro"
				(at 26.67 -19.05 0)
				(effects
					(font
						(size 1.27 1.27)
						(thickness 0.15)
					)
					(justify left bottom)
					(hide yes)
				)
			)
			(property "License" "Apache-2.0"
				(at 26.67 -21.59 0)
				(effects
					(font
						(size 1.27 1.27)
						(thickness 0.15)
					)
					(justify left bottom)
					(hide yes)
				)
			)
			(property "ki_keywords" "CONNECTOR, SMT"
				(at 0 0 0)
				(effects
					(font
						(size 1.27 1.27)
					)
					(hide yes)
				)
			)
			(symbol "JST_SH_1x2_SM02B-SRSS-TB-LF-SN_1_1"
				(rectangle
					(start 2.54 -4.953)
					(end 3.81 -5.207)
					(stroke
						(width 0.254)
						(type default)
					)
					(fill
						(type background)
					)
				)
				(rectangle
					(start 2.54 -2.413)
					(end 3.81 -2.667)
					(stroke
						(width 0.254)
						(type default)
					)
					(fill
						(type background)
					)
				)
				(rectangle
					(start 2.54 0.127)
					(end 3.81 -0.127)
					(stroke
						(width 0.254)
						(type default)
					)
					(fill
						(type background)
					)
				)
				(rectangle
					(start 2.54 2.54)
					(end 5.08 -7.62)
					(stroke
						(width 0.254)
						(type default)
					)
					(fill
						(type background)
					)
				)
				(pin passive line
					(at 0 0 0)
					(length 2.54)
					(name "~"
						(effects
							(font
								(size 1.27 1.27)
							)
						)
					)
					(number "1"
						(effects
							(font
								(size 1.27 1.27)
							)
						)
					)
				)
				(pin passive line
					(at 0 -2.54 0)
					(length 2.54)
					(name "~"
						(effects
							(font
								(size 1.27 1.27)
							)
						)
					)
					(number "2"
						(effects
							(font
								(size 1.27 1.27)
							)
						)
					)
				)
				(pin passive line
					(at 0 -5.08 0)
					(length 2.54)
					(name "~"
						(effects
							(font
								(size 1.27 1.27)
							)
						)
					)
					(number "MP"
						(effects
							(font
								(size 1.27 1.27)
							)
						)
					)
				)
			)
		)
	(symbol "antmicroWire2BoardConnectors:JST_XH_1x2_S2B-XH-A-LF-SN"
			(exclude_from_sim no)
			(in_bom yes)
			(on_board yes)
			(property "Reference" "J"
				(at 25.4 -2.54 0)
				(effects
					(font
						(size 1.27 1.27)
						(thickness 0.15)
					)
					(justify left bottom)
				)
			)
			(property "Value" "JST_XH_1x2_S2B-XH-A-LF-SN"
				(at 25.4 -10.16 0)
				(effects
					(font
						(size 1.27 1.27)
						(thickness 0.15)
					)
					(justify left bottom)
					(hide yes)
				)
			)
			(property "Footprint" "antmicro-footprints:Conn_JST_XH_1x2_S2B-XH-A-LF-SN"
				(at 25.4 -12.7 0)
				(effects
					(font
						(size 1.27 1.27)
						(thickness 0.15)
					)
					(justify left bottom)
					(hide yes)
				)
			)
			(property "Datasheet" "https://www.tme.eu/Document/0a99312bb6c67d3f0f7869fe9a023cea/XH.pdf"
				(at 25.4 -15.24 0)
				(effects
					(font
						(size 1.27 1.27)
						(thickness 0.15)
					)
					(justify left bottom)
					(hide yes)
				)
			)
			(property "Description" "Connector Header Through Hole, Right Angle 2 position 0.098\" (2.50mm)"
				(at 0 0 0)
				(effects
					(font
						(size 1.27 1.27)
					)
					(hide yes)
				)
			)
			(property "MPN" "S2B-XH-A(LF)(SN)"
				(at 25.4 -5.08 0)
				(effects
					(font
						(size 1.27 1.27)
						(thickness 0.15)
					)
					(justify left bottom)
				)
			)
			(property "Manufacturer" "JST Automotive Connectors"
				(at 25.4 -7.62 0)
				(effects
					(font
						(size 1.27 1.27)
						(thickness 0.15)
					)
					(justify left bottom)
					(hide yes)
				)
			)
			(property "Author" "Antmicro"
				(at 25.4 -17.78 0)
				(effects
					(font
						(size 1.27 1.27)
						(thickness 0.15)
					)
					(justify left bottom)
					(hide yes)
				)
			)
			(property "License" "Apache-2.0"
				(at 25.4 -20.32 0)
				(effects
					(font
						(size 1.27 1.27)
						(thickness 0.15)
					)
					(justify left bottom)
					(hide yes)
				)
			)
			(property "ki_keywords" "THT, WIRE-BOARD, CONNECTOR, MALE, HEADER"
				(at 0 0 0)
				(effects
					(font
						(size 1.27 1.27)
					)
					(hide yes)
				)
			)
			(symbol "JST_XH_1x2_S2B-XH-A-LF-SN_1_1"
				(rectangle
					(start 2.54 -2.413)
					(end 3.81 -2.667)
					(stroke
						(width 0.254)
						(type default)
					)
					(fill
						(type background)
					)
				)
				(rectangle
					(start 2.54 0.127)
					(end 3.81 -0.127)
					(stroke
						(width 0.254)
						(type default)
					)
					(fill
						(type background)
					)
				)
				(rectangle
					(start 2.54 2.54)
					(end 5.08 -5.08)
					(stroke
						(width 0.254)
						(type default)
					)
					(fill
						(type background)
					)
				)
				(pin input line
					(at 0 0 0)
					(length 2.54)
					(name "~"
						(effects
							(font
								(size 1.27 1.27)
							)
						)
					)
					(number "1"
						(effects
							(font
								(size 1.27 1.27)
							)
						)
					)
				)
				(pin input line
					(at 0 -2.54 0)
					(length 2.54)
					(name "~"
						(effects
							(font
								(size 1.27 1.27)
							)
						)
					)
					(number "2"
						(effects
							(font
								(size 1.27 1.27)
							)
						)
					)
				)
			)
		)
	(symbol "antmicroWire2BoardConnectors:JST_XH_1x4_S4B-XH-A-LF-SN"
			(exclude_from_sim no)
			(in_bom yes)
			(on_board yes)
			(property "Reference" "J"
				(at 25.4 -2.54 0)
				(effects
					(font
						(size 1.27 1.27)
						(thickness 0.15)
					)
					(justify left bottom)
				)
			)
			(property "Value" "JST_XH_1x4_S4B-XH-A-LF-SN"
				(at 25.4 -7.62 0)
				(effects
					(font
						(size 1.27 1.27)
						(thickness 0.15)
					)
					(justify left bottom)
					(hide yes)
				)
			)
			(property "Footprint" "antmicro-footprints:Conn_JST_XH_1x4_S4B-XH-A-LF-SN"
				(at 25.4 -10.16 0)
				(effects
					(font
						(size 1.27 1.27)
						(thickness 0.15)
					)
					(justify left bottom)
					(hide yes)
				)
			)
			(property "Datasheet" "https://www.tme.eu/Document/0a99312bb6c67d3f0f7869fe9a023cea/XH.pdf"
				(at 25.4 -12.7 0)
				(effects
					(font
						(size 1.27 1.27)
						(thickness 0.15)
					)
					(justify left bottom)
					(hide yes)
				)
			)
			(property "Description" "Pin Header, Right Angle, Wire-to-Board, 1 Rows, 4 Contacts, Surface Mount Right Angle, Pitch 2.5mm"
				(at 0 0 0)
				(effects
					(font
						(size 1.27 1.27)
					)
					(hide yes)
				)
			)
			(property "MPN" "S4B-XH-A (LF)(SN)"
				(at 25.4 -5.08 0)
				(effects
					(font
						(size 1.27 1.27)
						(thickness 0.15)
					)
					(justify left bottom)
				)
			)
			(property "Manufacturer" "JST Automotive Connectors"
				(at 25.4 -15.24 0)
				(effects
					(font
						(size 1.27 1.27)
						(thickness 0.15)
					)
					(justify left bottom)
					(hide yes)
				)
			)
			(property "Author" "Antmicro"
				(at 25.4 -17.78 0)
				(effects
					(font
						(size 1.27 1.27)
						(thickness 0.15)
					)
					(justify left bottom)
					(hide yes)
				)
			)
			(property "License" "Apache-2.0"
				(at 25.4 -20.32 0)
				(effects
					(font
						(size 1.27 1.27)
						(thickness 0.15)
					)
					(justify left bottom)
					(hide yes)
				)
			)
			(property "ki_keywords" "THT, WIRE-BOARD, CONNECTOR, MALE, HEADER"
				(at 0 0 0)
				(effects
					(font
						(size 1.27 1.27)
					)
					(hide yes)
				)
			)
			(symbol "JST_XH_1x4_S4B-XH-A-LF-SN_1_1"
				(rectangle
					(start 2.54 -7.493)
					(end 3.81 -7.747)
					(stroke
						(width 0.254)
						(type default)
					)
					(fill
						(type background)
					)
				)
				(rectangle
					(start 2.54 -4.953)
					(end 3.81 -5.207)
					(stroke
						(width 0.254)
						(type default)
					)
					(fill
						(type background)
					)
				)
				(rectangle
					(start 2.54 -2.413)
					(end 3.81 -2.667)
					(stroke
						(width 0.254)
						(type default)
					)
					(fill
						(type background)
					)
				)
				(rectangle
					(start 2.54 0.127)
					(end 3.81 -0.127)
					(stroke
						(width 0.254)
						(type default)
					)
					(fill
						(type background)
					)
				)
				(rectangle
					(start 2.54 2.54)
					(end 5.08 -10.16)
					(stroke
						(width 0.254)
						(type default)
					)
					(fill
						(type background)
					)
				)
				(pin passive line
					(at 0 0 0)
					(length 2.54)
					(name "~"
						(effects
							(font
								(size 1.27 1.27)
							)
						)
					)
					(number "1"
						(effects
							(font
								(size 1.27 1.27)
							)
						)
					)
				)
				(pin passive line
					(at 0 -2.54 0)
					(length 2.54)
					(name "~"
						(effects
							(font
								(size 1.27 1.27)
							)
						)
					)
					(number "2"
						(effects
							(font
								(size 1.27 1.27)
							)
						)
					)
				)
				(pin passive line
					(at 0 -5.08 0)
					(length 2.54)
					(name "~"
						(effects
							(font
								(size 1.27 1.27)
							)
						)
					)
					(number "3"
						(effects
							(font
								(size 1.27 1.27)
							)
						)
					)
				)
				(pin passive line
					(at 0 -7.62 0)
					(length 2.54)
					(name "~"
						(effects
							(font
								(size 1.27 1.27)
							)
						)
					)
					(number "4"
						(effects
							(font
								(size 1.27 1.27)
							)
						)
					)
				)
			)
		)
	(symbol "antmicroWire2BoardConnectors:Molex_Nano-Fit_1x2_1053131202"
			(exclude_from_sim no)
			(in_bom yes)
			(on_board yes)
			(property "Reference" "J"
				(at 13.335 -2.54 0)
				(effects
					(font
						(size 1.27 1.27)
						(thickness 0.15)
					)
					(justify left bottom)
				)
			)
			(property "Value" "Molex_Nano-Fit_1x2_1053131202"
				(at 13.335 -5.08 0)
				(effects
					(font
						(size 1.27 1.27)
						(thickness 0.15)
					)
					(justify left bottom)
					(hide yes)
				)
			)
			(property "Footprint" "antmicro-footprints:Conn_Molex_Nano-Fit_1x2_1053131102"
				(at 13.335 -7.62 0)
				(effects
					(font
						(size 1.27 1.27)
						(thickness 0.15)
					)
					(justify left bottom)
					(hide yes)
				)
			)
			(property "Datasheet" "https://tools.molex.com/pdm_docs/ps/PS-105300-100-001.pdf"
				(at 13.335 -10.16 0)
				(effects
					(font
						(size 1.27 1.27)
						(thickness 0.15)
					)
					(justify left bottom)
					(hide yes)
				)
			)
			(property "Description" "Rectangular connector, header, Through Hole, Right Angle 2 position"
				(at 0 0 0)
				(effects
					(font
						(size 1.27 1.27)
					)
					(hide yes)
				)
			)
			(property "Manufacturer" "Molex"
				(at 13.335 -12.7 0)
				(effects
					(font
						(size 1.27 1.27)
						(thickness 0.15)
					)
					(justify left bottom)
					(hide yes)
				)
			)
			(property "MPN" "1053131202"
				(at 13.335 -15.24 0)
				(effects
					(font
						(size 1.27 1.27)
						(thickness 0.15)
					)
					(justify left bottom)
				)
			)
			(property "Author" "Antmicro"
				(at 13.335 -17.78 0)
				(effects
					(font
						(size 1.27 1.27)
						(thickness 0.15)
					)
					(justify left bottom)
					(hide yes)
				)
			)
			(property "License" "Apache-2.0"
				(at 13.335 -20.32 0)
				(effects
					(font
						(size 1.27 1.27)
						(thickness 0.15)
					)
					(justify left bottom)
					(hide yes)
				)
			)
			(property "ki_keywords" "CONNECTOR, THT"
				(at 0 0 0)
				(effects
					(font
						(size 1.27 1.27)
					)
					(hide yes)
				)
			)
			(symbol "Molex_Nano-Fit_1x2_1053131202_1_1"
				(rectangle
					(start 2.54 -2.413)
					(end 3.81 -2.667)
					(stroke
						(width 0.254)
						(type default)
					)
					(fill
						(type background)
					)
				)
				(rectangle
					(start 2.54 0.127)
					(end 3.81 -0.127)
					(stroke
						(width 0.254)
						(type default)
					)
					(fill
						(type background)
					)
				)
				(rectangle
					(start 2.54 1.27)
					(end 5.08 -3.81)
					(stroke
						(width 0.254)
						(type default)
					)
					(fill
						(type background)
					)
				)
				(pin input line
					(at 0 0 0)
					(length 2.54)
					(name "~"
						(effects
							(font
								(size 1.27 1.27)
							)
						)
					)
					(number "1"
						(effects
							(font
								(size 1.27 1.27)
							)
						)
					)
				)
				(pin input line
					(at 0 -2.54 0)
					(length 2.54)
					(name "~"
						(effects
							(font
								(size 1.27 1.27)
							)
						)
					)
					(number "2"
						(effects
							(font
								(size 1.27 1.27)
							)
						)
					)
				)
			)
		)
	(symbol "antmicropower:GND"
			(power)
			(pin_numbers hide)
			(pin_names hide)
			(exclude_from_sim no)
			(in_bom yes)
			(on_board yes)
			(property "Reference" "#PWR"
				(at 8.89 -2.54 0)
				(effects
					(font
						(size 1.27 1.27)
						(thickness 0.15)
					)
					(justify left bottom)
					(hide yes)
				)
			)
			(property "Value" "GND"
				(at 8.89 -5.08 0)
				(effects
					(font
						(size 1.27 1.27)
						(thickness 0.15)
					)
					(justify left bottom)
				)
			)
			(property "Footprint" ""
				(at 8.89 -7.62 0)
				(effects
					(font
						(size 1.27 1.27)
						(thickness 0.15)
					)
					(justify left bottom)
					(hide yes)
				)
			)
			(property "Datasheet" ""
				(at 8.89 -12.7 0)
				(effects
					(font
						(size 1.27 1.27)
						(thickness 0.15)
					)
					(justify left bottom)
					(hide yes)
				)
			)
			(property "Description" ""
				(at 0 0 0)
				(effects
					(font
						(size 1.27 1.27)
					)
					(hide yes)
				)
			)
			(property "Author" "Antmicro"
				(at 8.89 -7.62 0)
				(effects
					(font
						(size 1.27 1.27)
						(thickness 0.15)
					)
					(justify left bottom)
					(hide yes)
				)
			)
			(property "License" "Apache-2.0"
				(at 8.89 -10.16 0)
				(effects
					(font
						(size 1.27 1.27)
						(thickness 0.15)
					)
					(justify left bottom)
					(hide yes)
				)
			)
			(symbol "GND_1_1"
				(polyline
					(pts
						(xy 0 0) (xy 0 -1.27) (xy 1.27 -1.27) (xy 0 -2.54) (xy -1.27 -1.27) (xy 0 -1.27)
					)
					(stroke
						(width 0)
						(type default)
					)
					(fill
						(type none)
					)
				)
				(pin power_in line
					(at 0 0 270)
					(length 0)
					(name "GND"
						(effects
							(font
								(size 1.27 1.27)
							)
						)
					)
					(number "1"
						(effects
							(font
								(size 1.27 1.27)
							)
						)
					)
				)
			)
		)
	(symbol "antmicropower:PWR_FLAG"
			(power)
			(pin_numbers hide)
			(pin_names
				(offset 0) hide)
			(exclude_from_sim no)
			(in_bom yes)
			(on_board yes)
			(property "Reference" "#FLG"
				(at 0 1.905 0)
				(effects
					(font
						(size 1.27 1.27)
					)
					(hide yes)
				)
			)
			(property "Value" "PWR_FLAG"
				(at 0 3.81 0)
				(effects
					(font
						(size 1.27 1.27)
					)
				)
			)
			(property "Footprint" ""
				(at 0 0 0)
				(effects
					(font
						(size 1.27 1.27)
					)
					(hide yes)
				)
			)
			(property "Datasheet" ""
				(at 0 0 0)
				(effects
					(font
						(size 1.27 1.27)
					)
					(hide yes)
				)
			)
			(property "Description" ""
				(at 0 0 0)
				(effects
					(font
						(size 1.27 1.27)
					)
					(hide yes)
				)
			)
			(symbol "PWR_FLAG_0_0"
				(pin power_out line
					(at 0 0 90)
					(length 0)
					(name "pwr"
						(effects
							(font
								(size 1.27 1.27)
							)
						)
					)
					(number "1"
						(effects
							(font
								(size 1.27 1.27)
							)
						)
					)
				)
			)
			(symbol "PWR_FLAG_0_1"
				(polyline
					(pts
						(xy 0 0) (xy 0 1.27) (xy -1.016 1.905) (xy 0 2.54) (xy 1.016 1.905) (xy 0 1.27)
					)
					(stroke
						(width 0)
						(type default)
					)
					(fill
						(type none)
					)
				)
			)
		)
	(symbol "thunderbolt-gpu-adapter:C_1u_0402_10"
			(pin_numbers hide)
			(pin_names hide)
			(exclude_from_sim no)
			(in_bom yes)
			(on_board yes)
			(property "Reference" "C"
				(at 20.32 -5.08 0)
				(effects
					(font
						(size 1.27 1.27)
						(thickness 0.15)
					)
					(justify left bottom)
				)
			)
			(property "Value" "C_1u_0402_10"
				(at 20.32 -10.16 0)
				(effects
					(font
						(size 1.27 1.27)
						(thickness 0.15)
					)
					(justify left bottom)
					(hide yes)
				)
			)
			(property "Footprint" "thunderbolt-gpu-adapter-footprints:C_0402_1005Metric"
				(at 20.32 -12.7 0)
				(effects
					(font
						(size 1.27 1.27)
						(thickness 0.15)
					)
					(justify left bottom)
					(hide yes)
				)
			)
			(property "Datasheet" " "
				(at 20.32 -15.24 0)
				(effects
					(font
						(size 1.27 1.27)
						(thickness 0.15)
					)
					(justify left bottom)
					(hide yes)
				)
			)
			(property "Description" " "
				(at 0 0 0)
				(effects
					(font
						(size 1.27 1.27)
					)
					(hide yes)
				)
			)
			(property "MPN" "C1005X6S1A105K050BC"
				(at 20.32 -17.78 0)
				(effects
					(font
						(size 1.27 1.27)
						(thickness 0.15)
					)
					(justify left bottom)
					(hide yes)
				)
			)
			(property "Manufacturer" "TDK"
				(at 20.32 -20.32 0)
				(effects
					(font
						(size 1.27 1.27)
						(thickness 0.15)
					)
					(justify left bottom)
					(hide yes)
				)
			)
			(property "License" "Apache-2.0"
				(at 20.32 -22.86 0)
				(effects
					(font
						(size 1.27 1.27)
						(thickness 0.15)
					)
					(justify left bottom)
					(hide yes)
				)
			)
			(property "Author" "Antmicro"
				(at 20.32 -25.4 0)
				(effects
					(font
						(size 1.27 1.27)
						(thickness 0.15)
					)
					(justify left bottom)
					(hide yes)
				)
			)
			(property "Val" "1u"
				(at 20.32 -7.62 0)
				(effects
					(font
						(size 1.27 1.27)
						(thickness 0.15)
					)
					(justify left bottom)
				)
			)
			(property "Voltage" ""
				(at 20.32 -27.94 0)
				(effects
					(font
						(size 1.27 1.27)
					)
					(justify left bottom)
					(hide yes)
				)
			)
			(property "Dielectric" ""
				(at 20.32 -30.48 0)
				(effects
					(font
						(size 1.27 1.27)
					)
					(justify left bottom)
					(hide yes)
				)
			)
			(symbol "C_1u_0402_10_0_1"
				(polyline
					(pts
						(xy 2.032 -1.524) (xy 2.032 1.524)
					)
					(stroke
						(width 0.3048)
						(type default)
					)
					(fill
						(type none)
					)
				)
				(polyline
					(pts
						(xy 3.048 -1.524) (xy 3.048 1.524)
					)
					(stroke
						(width 0.3302)
						(type default)
					)
					(fill
						(type none)
					)
				)
			)
			(symbol "C_1u_0402_10_1_1"
				(pin passive line
					(at 0 0 0)
					(length 2.032)
					(name "~"
						(effects
							(font
								(size 1.27 1.27)
							)
						)
					)
					(number "1"
						(effects
							(font
								(size 1.27 1.27)
							)
						)
					)
				)
				(pin passive line
					(at 5.08 0 180)
					(length 2.032)
					(name "~"
						(effects
							(font
								(size 1.27 1.27)
							)
						)
					)
					(number "2"
						(effects
							(font
								(size 1.27 1.27)
							)
						)
					)
				)
			)
		)
	(symbol "thunderbolt-gpu-adapter:C_1u_0402_11"
			(pin_numbers hide)
			(pin_names hide)
			(exclude_from_sim no)
			(in_bom yes)
			(on_board yes)
			(property "Reference" "C"
				(at 20.32 -5.08 0)
				(effects
					(font
						(size 1.27 1.27)
						(thickness 0.15)
					)
					(justify left bottom)
				)
			)
			(property "Value" "C_1u_0402_11"
				(at 20.32 -10.16 0)
				(effects
					(font
						(size 1.27 1.27)
						(thickness 0.15)
					)
					(justify left bottom)
					(hide yes)
				)
			)
			(property "Footprint" "thunderbolt-gpu-adapter-footprints:C_0402_1005Metric"
				(at 20.32 -12.7 0)
				(effects
					(font
						(size 1.27 1.27)
						(thickness 0.15)
					)
					(justify left bottom)
					(hide yes)
				)
			)
			(property "Datasheet" " "
				(at 20.32 -15.24 0)
				(effects
					(font
						(size 1.27 1.27)
						(thickness 0.15)
					)
					(justify left bottom)
					(hide yes)
				)
			)
			(property "Description" " "
				(at 0 0 0)
				(effects
					(font
						(size 1.27 1.27)
					)
					(hide yes)
				)
			)
			(property "MPN" "C1005X6S1A105K050BC"
				(at 20.32 -17.78 0)
				(effects
					(font
						(size 1.27 1.27)
						(thickness 0.15)
					)
					(justify left bottom)
					(hide yes)
				)
			)
			(property "Manufacturer" "TDK"
				(at 20.32 -20.32 0)
				(effects
					(font
						(size 1.27 1.27)
						(thickness 0.15)
					)
					(justify left bottom)
					(hide yes)
				)
			)
			(property "License" "Apache-2.0"
				(at 20.32 -22.86 0)
				(effects
					(font
						(size 1.27 1.27)
						(thickness 0.15)
					)
					(justify left bottom)
					(hide yes)
				)
			)
			(property "Author" "Antmicro"
				(at 20.32 -25.4 0)
				(effects
					(font
						(size 1.27 1.27)
						(thickness 0.15)
					)
					(justify left bottom)
					(hide yes)
				)
			)
			(property "Val" "1u"
				(at 20.32 -7.62 0)
				(effects
					(font
						(size 1.27 1.27)
						(thickness 0.15)
					)
					(justify left bottom)
				)
			)
			(property "Voltage" ""
				(at 20.32 -27.94 0)
				(effects
					(font
						(size 1.27 1.27)
					)
					(justify left bottom)
					(hide yes)
				)
			)
			(property "Dielectric" ""
				(at 20.32 -30.48 0)
				(effects
					(font
						(size 1.27 1.27)
					)
					(justify left bottom)
					(hide yes)
				)
			)
			(symbol "C_1u_0402_11_0_1"
				(polyline
					(pts
						(xy 2.032 -1.524) (xy 2.032 1.524)
					)
					(stroke
						(width 0.3048)
						(type default)
					)
					(fill
						(type none)
					)
				)
				(polyline
					(pts
						(xy 3.048 -1.524) (xy 3.048 1.524)
					)
					(stroke
						(width 0.3302)
						(type default)
					)
					(fill
						(type none)
					)
				)
			)
			(symbol "C_1u_0402_11_1_1"
				(pin passive line
					(at 0 0 0)
					(length 2.032)
					(name "~"
						(effects
							(font
								(size 1.27 1.27)
							)
						)
					)
					(number "1"
						(effects
							(font
								(size 1.27 1.27)
							)
						)
					)
				)
				(pin passive line
					(at 5.08 0 180)
					(length 2.032)
					(name "~"
						(effects
							(font
								(size 1.27 1.27)
							)
						)
					)
					(number "2"
						(effects
							(font
								(size 1.27 1.27)
							)
						)
					)
				)
			)
		)
	(symbol "thunderbolt-gpu-adapter:C_1u_0402_12"
			(pin_numbers hide)
			(pin_names hide)
			(exclude_from_sim no)
			(in_bom yes)
			(on_board yes)
			(property "Reference" "C"
				(at 20.32 -5.08 0)
				(effects
					(font
						(size 1.27 1.27)
						(thickness 0.15)
					)
					(justify left bottom)
				)
			)
			(property "Value" "C_1u_0402_12"
				(at 20.32 -10.16 0)
				(effects
					(font
						(size 1.27 1.27)
						(thickness 0.15)
					)
					(justify left bottom)
					(hide yes)
				)
			)
			(property "Footprint" "thunderbolt-gpu-adapter-footprints:C_0402_1005Metric"
				(at 20.32 -12.7 0)
				(effects
					(font
						(size 1.27 1.27)
						(thickness 0.15)
					)
					(justify left bottom)
					(hide yes)
				)
			)
			(property "Datasheet" " "
				(at 20.32 -15.24 0)
				(effects
					(font
						(size 1.27 1.27)
						(thickness 0.15)
					)
					(justify left bottom)
					(hide yes)
				)
			)
			(property "Description" " "
				(at 0 0 0)
				(effects
					(font
						(size 1.27 1.27)
					)
					(hide yes)
				)
			)
			(property "MPN" "C1005X6S1A105K050BC"
				(at 20.32 -17.78 0)
				(effects
					(font
						(size 1.27 1.27)
						(thickness 0.15)
					)
					(justify left bottom)
					(hide yes)
				)
			)
			(property "Manufacturer" "TDK"
				(at 20.32 -20.32 0)
				(effects
					(font
						(size 1.27 1.27)
						(thickness 0.15)
					)
					(justify left bottom)
					(hide yes)
				)
			)
			(property "License" "Apache-2.0"
				(at 20.32 -22.86 0)
				(effects
					(font
						(size 1.27 1.27)
						(thickness 0.15)
					)
					(justify left bottom)
					(hide yes)
				)
			)
			(property "Author" "Antmicro"
				(at 20.32 -25.4 0)
				(effects
					(font
						(size 1.27 1.27)
						(thickness 0.15)
					)
					(justify left bottom)
					(hide yes)
				)
			)
			(property "Val" "1u"
				(at 20.32 -7.62 0)
				(effects
					(font
						(size 1.27 1.27)
						(thickness 0.15)
					)
					(justify left bottom)
				)
			)
			(property "Voltage" ""
				(at 20.32 -27.94 0)
				(effects
					(font
						(size 1.27 1.27)
					)
					(justify left bottom)
					(hide yes)
				)
			)
			(property "Dielectric" ""
				(at 20.32 -30.48 0)
				(effects
					(font
						(size 1.27 1.27)
					)
					(justify left bottom)
					(hide yes)
				)
			)
			(symbol "C_1u_0402_12_0_1"
				(polyline
					(pts
						(xy 2.032 -1.524) (xy 2.032 1.524)
					)
					(stroke
						(width 0.3048)
						(type default)
					)
					(fill
						(type none)
					)
				)
				(polyline
					(pts
						(xy 3.048 -1.524) (xy 3.048 1.524)
					)
					(stroke
						(width 0.3302)
						(type default)
					)
					(fill
						(type none)
					)
				)
			)
			(symbol "C_1u_0402_12_1_1"
				(pin passive line
					(at 0 0 0)
					(length 2.032)
					(name "~"
						(effects
							(font
								(size 1.27 1.27)
							)
						)
					)
					(number "1"
						(effects
							(font
								(size 1.27 1.27)
							)
						)
					)
				)
				(pin passive line
					(at 5.08 0 180)
					(length 2.032)
					(name "~"
						(effects
							(font
								(size 1.27 1.27)
							)
						)
					)
					(number "2"
						(effects
							(font
								(size 1.27 1.27)
							)
						)
					)
				)
			)
		)
	(symbol "thunderbolt-gpu-adapter:C_1u_0402_13"
			(pin_numbers hide)
			(pin_names hide)
			(exclude_from_sim no)
			(in_bom yes)
			(on_board yes)
			(property "Reference" "C"
				(at 20.32 -5.08 0)
				(effects
					(font
						(size 1.27 1.27)
						(thickness 0.15)
					)
					(justify left bottom)
				)
			)
			(property "Value" "C_1u_0402_13"
				(at 20.32 -10.16 0)
				(effects
					(font
						(size 1.27 1.27)
						(thickness 0.15)
					)
					(justify left bottom)
					(hide yes)
				)
			)
			(property "Footprint" "thunderbolt-gpu-adapter-footprints:C_0402_1005Metric"
				(at 20.32 -12.7 0)
				(effects
					(font
						(size 1.27 1.27)
						(thickness 0.15)
					)
					(justify left bottom)
					(hide yes)
				)
			)
			(property "Datasheet" " "
				(at 20.32 -15.24 0)
				(effects
					(font
						(size 1.27 1.27)
						(thickness 0.15)
					)
					(justify left bottom)
					(hide yes)
				)
			)
			(property "Description" " "
				(at 0 0 0)
				(effects
					(font
						(size 1.27 1.27)
					)
					(hide yes)
				)
			)
			(property "MPN" "C1005X6S1A105K050BC"
				(at 20.32 -17.78 0)
				(effects
					(font
						(size 1.27 1.27)
						(thickness 0.15)
					)
					(justify left bottom)
					(hide yes)
				)
			)
			(property "Manufacturer" "TDK"
				(at 20.32 -20.32 0)
				(effects
					(font
						(size 1.27 1.27)
						(thickness 0.15)
					)
					(justify left bottom)
					(hide yes)
				)
			)
			(property "License" "Apache-2.0"
				(at 20.32 -22.86 0)
				(effects
					(font
						(size 1.27 1.27)
						(thickness 0.15)
					)
					(justify left bottom)
					(hide yes)
				)
			)
			(property "Author" "Antmicro"
				(at 20.32 -25.4 0)
				(effects
					(font
						(size 1.27 1.27)
						(thickness 0.15)
					)
					(justify left bottom)
					(hide yes)
				)
			)
			(property "Val" "1u"
				(at 20.32 -7.62 0)
				(effects
					(font
						(size 1.27 1.27)
						(thickness 0.15)
					)
					(justify left bottom)
				)
			)
			(property "Voltage" ""
				(at 20.32 -27.94 0)
				(effects
					(font
						(size 1.27 1.27)
					)
					(justify left bottom)
					(hide yes)
				)
			)
			(property "Dielectric" ""
				(at 20.32 -30.48 0)
				(effects
					(font
						(size 1.27 1.27)
					)
					(justify left bottom)
					(hide yes)
				)
			)
			(symbol "C_1u_0402_13_0_1"
				(polyline
					(pts
						(xy 2.032 -1.524) (xy 2.032 1.524)
					)
					(stroke
						(width 0.3048)
						(type default)
					)
					(fill
						(type none)
					)
				)
				(polyline
					(pts
						(xy 3.048 -1.524) (xy 3.048 1.524)
					)
					(stroke
						(width 0.3302)
						(type default)
					)
					(fill
						(type none)
					)
				)
			)
			(symbol "C_1u_0402_13_1_1"
				(pin passive line
					(at 0 0 0)
					(length 2.032)
					(name "~"
						(effects
							(font
								(size 1.27 1.27)
							)
						)
					)
					(number "1"
						(effects
							(font
								(size 1.27 1.27)
							)
						)
					)
				)
				(pin passive line
					(at 5.08 0 180)
					(length 2.032)
					(name "~"
						(effects
							(font
								(size 1.27 1.27)
							)
						)
					)
					(number "2"
						(effects
							(font
								(size 1.27 1.27)
							)
						)
					)
				)
			)
		)
	(symbol "thunderbolt-gpu-adapter:C_1u_0402_14"
			(pin_numbers hide)
			(pin_names hide)
			(exclude_from_sim no)
			(in_bom yes)
			(on_board yes)
			(property "Reference" "C"
				(at 20.32 -5.08 0)
				(effects
					(font
						(size 1.27 1.27)
						(thickness 0.15)
					)
					(justify left bottom)
				)
			)
			(property "Value" "C_1u_0402_14"
				(at 20.32 -10.16 0)
				(effects
					(font
						(size 1.27 1.27)
						(thickness 0.15)
					)
					(justify left bottom)
					(hide yes)
				)
			)
			(property "Footprint" "thunderbolt-gpu-adapter-footprints:C_0402_1005Metric"
				(at 20.32 -12.7 0)
				(effects
					(font
						(size 1.27 1.27)
						(thickness 0.15)
					)
					(justify left bottom)
					(hide yes)
				)
			)
			(property "Datasheet" " "
				(at 20.32 -15.24 0)
				(effects
					(font
						(size 1.27 1.27)
						(thickness 0.15)
					)
					(justify left bottom)
					(hide yes)
				)
			)
			(property "Description" " "
				(at 0 0 0)
				(effects
					(font
						(size 1.27 1.27)
					)
					(hide yes)
				)
			)
			(property "MPN" "C1005X6S1A105K050BC"
				(at 20.32 -17.78 0)
				(effects
					(font
						(size 1.27 1.27)
						(thickness 0.15)
					)
					(justify left bottom)
					(hide yes)
				)
			)
			(property "Manufacturer" "TDK"
				(at 20.32 -20.32 0)
				(effects
					(font
						(size 1.27 1.27)
						(thickness 0.15)
					)
					(justify left bottom)
					(hide yes)
				)
			)
			(property "License" "Apache-2.0"
				(at 20.32 -22.86 0)
				(effects
					(font
						(size 1.27 1.27)
						(thickness 0.15)
					)
					(justify left bottom)
					(hide yes)
				)
			)
			(property "Author" "Antmicro"
				(at 20.32 -25.4 0)
				(effects
					(font
						(size 1.27 1.27)
						(thickness 0.15)
					)
					(justify left bottom)
					(hide yes)
				)
			)
			(property "Val" "1u"
				(at 20.32 -7.62 0)
				(effects
					(font
						(size 1.27 1.27)
						(thickness 0.15)
					)
					(justify left bottom)
				)
			)
			(property "Voltage" ""
				(at 20.32 -27.94 0)
				(effects
					(font
						(size 1.27 1.27)
					)
					(justify left bottom)
					(hide yes)
				)
			)
			(property "Dielectric" ""
				(at 20.32 -30.48 0)
				(effects
					(font
						(size 1.27 1.27)
					)
					(justify left bottom)
					(hide yes)
				)
			)
			(symbol "C_1u_0402_14_0_1"
				(polyline
					(pts
						(xy 2.032 -1.524) (xy 2.032 1.524)
					)
					(stroke
						(width 0.3048)
						(type default)
					)
					(fill
						(type none)
					)
				)
				(polyline
					(pts
						(xy 3.048 -1.524) (xy 3.048 1.524)
					)
					(stroke
						(width 0.3302)
						(type default)
					)
					(fill
						(type none)
					)
				)
			)
			(symbol "C_1u_0402_14_1_1"
				(pin passive line
					(at 0 0 0)
					(length 2.032)
					(name "~"
						(effects
							(font
								(size 1.27 1.27)
							)
						)
					)
					(number "1"
						(effects
							(font
								(size 1.27 1.27)
							)
						)
					)
				)
				(pin passive line
					(at 5.08 0 180)
					(length 2.032)
					(name "~"
						(effects
							(font
								(size 1.27 1.27)
							)
						)
					)
					(number "2"
						(effects
							(font
								(size 1.27 1.27)
							)
						)
					)
				)
			)
		)
	(symbol "thunderbolt-gpu-adapter:C_1u_0402_15"
			(pin_numbers hide)
			(pin_names hide)
			(exclude_from_sim no)
			(in_bom yes)
			(on_board yes)
			(property "Reference" "C"
				(at 20.32 -5.08 0)
				(effects
					(font
						(size 1.27 1.27)
						(thickness 0.15)
					)
					(justify left bottom)
				)
			)
			(property "Value" "C_1u_0402_15"
				(at 20.32 -10.16 0)
				(effects
					(font
						(size 1.27 1.27)
						(thickness 0.15)
					)
					(justify left bottom)
					(hide yes)
				)
			)
			(property "Footprint" "thunderbolt-gpu-adapter-footprints:C_0402_1005Metric"
				(at 20.32 -12.7 0)
				(effects
					(font
						(size 1.27 1.27)
						(thickness 0.15)
					)
					(justify left bottom)
					(hide yes)
				)
			)
			(property "Datasheet" " "
				(at 20.32 -15.24 0)
				(effects
					(font
						(size 1.27 1.27)
						(thickness 0.15)
					)
					(justify left bottom)
					(hide yes)
				)
			)
			(property "Description" " "
				(at 0 0 0)
				(effects
					(font
						(size 1.27 1.27)
					)
					(hide yes)
				)
			)
			(property "MPN" "C1005X6S1A105K050BC"
				(at 20.32 -17.78 0)
				(effects
					(font
						(size 1.27 1.27)
						(thickness 0.15)
					)
					(justify left bottom)
					(hide yes)
				)
			)
			(property "Manufacturer" "TDK"
				(at 20.32 -20.32 0)
				(effects
					(font
						(size 1.27 1.27)
						(thickness 0.15)
					)
					(justify left bottom)
					(hide yes)
				)
			)
			(property "License" "Apache-2.0"
				(at 20.32 -22.86 0)
				(effects
					(font
						(size 1.27 1.27)
						(thickness 0.15)
					)
					(justify left bottom)
					(hide yes)
				)
			)
			(property "Author" "Antmicro"
				(at 20.32 -25.4 0)
				(effects
					(font
						(size 1.27 1.27)
						(thickness 0.15)
					)
					(justify left bottom)
					(hide yes)
				)
			)
			(property "Val" "1u"
				(at 20.32 -7.62 0)
				(effects
					(font
						(size 1.27 1.27)
						(thickness 0.15)
					)
					(justify left bottom)
				)
			)
			(property "Voltage" ""
				(at 20.32 -27.94 0)
				(effects
					(font
						(size 1.27 1.27)
					)
					(justify left bottom)
					(hide yes)
				)
			)
			(property "Dielectric" ""
				(at 20.32 -30.48 0)
				(effects
					(font
						(size 1.27 1.27)
					)
					(justify left bottom)
					(hide yes)
				)
			)
			(symbol "C_1u_0402_15_0_1"
				(polyline
					(pts
						(xy 2.032 -1.524) (xy 2.032 1.524)
					)
					(stroke
						(width 0.3048)
						(type default)
					)
					(fill
						(type none)
					)
				)
				(polyline
					(pts
						(xy 3.048 -1.524) (xy 3.048 1.524)
					)
					(stroke
						(width 0.3302)
						(type default)
					)
					(fill
						(type none)
					)
				)
			)
			(symbol "C_1u_0402_15_1_1"
				(pin passive line
					(at 0 0 0)
					(length 2.032)
					(name "~"
						(effects
							(font
								(size 1.27 1.27)
							)
						)
					)
					(number "1"
						(effects
							(font
								(size 1.27 1.27)
							)
						)
					)
				)
				(pin passive line
					(at 5.08 0 180)
					(length 2.032)
					(name "~"
						(effects
							(font
								(size 1.27 1.27)
							)
						)
					)
					(number "2"
						(effects
							(font
								(size 1.27 1.27)
							)
						)
					)
				)
			)
		)
	(symbol "thunderbolt-gpu-adapter:C_1u_0402_16"
			(pin_numbers hide)
			(pin_names hide)
			(exclude_from_sim no)
			(in_bom yes)
			(on_board yes)
			(property "Reference" "C"
				(at 20.32 -5.08 0)
				(effects
					(font
						(size 1.27 1.27)
						(thickness 0.15)
					)
					(justify left bottom)
				)
			)
			(property "Value" "C_1u_0402_16"
				(at 20.32 -10.16 0)
				(effects
					(font
						(size 1.27 1.27)
						(thickness 0.15)
					)
					(justify left bottom)
					(hide yes)
				)
			)
			(property "Footprint" "thunderbolt-gpu-adapter-footprints:C_0402_1005Metric"
				(at 20.32 -12.7 0)
				(effects
					(font
						(size 1.27 1.27)
						(thickness 0.15)
					)
					(justify left bottom)
					(hide yes)
				)
			)
			(property "Datasheet" " "
				(at 20.32 -15.24 0)
				(effects
					(font
						(size 1.27 1.27)
						(thickness 0.15)
					)
					(justify left bottom)
					(hide yes)
				)
			)
			(property "Description" " "
				(at 0 0 0)
				(effects
					(font
						(size 1.27 1.27)
					)
					(hide yes)
				)
			)
			(property "MPN" "C1005X6S1A105K050BC"
				(at 20.32 -17.78 0)
				(effects
					(font
						(size 1.27 1.27)
						(thickness 0.15)
					)
					(justify left bottom)
					(hide yes)
				)
			)
			(property "Manufacturer" "TDK"
				(at 20.32 -20.32 0)
				(effects
					(font
						(size 1.27 1.27)
						(thickness 0.15)
					)
					(justify left bottom)
					(hide yes)
				)
			)
			(property "License" "Apache-2.0"
				(at 20.32 -22.86 0)
				(effects
					(font
						(size 1.27 1.27)
						(thickness 0.15)
					)
					(justify left bottom)
					(hide yes)
				)
			)
			(property "Author" "Antmicro"
				(at 20.32 -25.4 0)
				(effects
					(font
						(size 1.27 1.27)
						(thickness 0.15)
					)
					(justify left bottom)
					(hide yes)
				)
			)
			(property "Val" "1u"
				(at 20.32 -7.62 0)
				(effects
					(font
						(size 1.27 1.27)
						(thickness 0.15)
					)
					(justify left bottom)
				)
			)
			(property "Voltage" ""
				(at 20.32 -27.94 0)
				(effects
					(font
						(size 1.27 1.27)
					)
					(justify left bottom)
					(hide yes)
				)
			)
			(property "Dielectric" ""
				(at 20.32 -30.48 0)
				(effects
					(font
						(size 1.27 1.27)
					)
					(justify left bottom)
					(hide yes)
				)
			)
			(symbol "C_1u_0402_16_0_1"
				(polyline
					(pts
						(xy 2.032 -1.524) (xy 2.032 1.524)
					)
					(stroke
						(width 0.3048)
						(type default)
					)
					(fill
						(type none)
					)
				)
				(polyline
					(pts
						(xy 3.048 -1.524) (xy 3.048 1.524)
					)
					(stroke
						(width 0.3302)
						(type default)
					)
					(fill
						(type none)
					)
				)
			)
			(symbol "C_1u_0402_16_1_1"
				(pin passive line
					(at 0 0 0)
					(length 2.032)
					(name "~"
						(effects
							(font
								(size 1.27 1.27)
							)
						)
					)
					(number "1"
						(effects
							(font
								(size 1.27 1.27)
							)
						)
					)
				)
				(pin passive line
					(at 5.08 0 180)
					(length 2.032)
					(name "~"
						(effects
							(font
								(size 1.27 1.27)
							)
						)
					)
					(number "2"
						(effects
							(font
								(size 1.27 1.27)
							)
						)
					)
				)
			)
		)
	(symbol "thunderbolt-gpu-adapter:C_1u_0402_17"
			(pin_numbers hide)
			(pin_names hide)
			(exclude_from_sim no)
			(in_bom yes)
			(on_board yes)
			(property "Reference" "C"
				(at 20.32 -5.08 0)
				(effects
					(font
						(size 1.27 1.27)
						(thickness 0.15)
					)
					(justify left bottom)
				)
			)
			(property "Value" "C_1u_0402_17"
				(at 20.32 -10.16 0)
				(effects
					(font
						(size 1.27 1.27)
						(thickness 0.15)
					)
					(justify left bottom)
					(hide yes)
				)
			)
			(property "Footprint" "thunderbolt-gpu-adapter-footprints:C_0402_1005Metric"
				(at 20.32 -12.7 0)
				(effects
					(font
						(size 1.27 1.27)
						(thickness 0.15)
					)
					(justify left bottom)
					(hide yes)
				)
			)
			(property "Datasheet" " "
				(at 20.32 -15.24 0)
				(effects
					(font
						(size 1.27 1.27)
						(thickness 0.15)
					)
					(justify left bottom)
					(hide yes)
				)
			)
			(property "Description" " "
				(at 0 0 0)
				(effects
					(font
						(size 1.27 1.27)
					)
					(hide yes)
				)
			)
			(property "MPN" "C1005X6S1A105K050BC"
				(at 20.32 -17.78 0)
				(effects
					(font
						(size 1.27 1.27)
						(thickness 0.15)
					)
					(justify left bottom)
					(hide yes)
				)
			)
			(property "Manufacturer" "TDK"
				(at 20.32 -20.32 0)
				(effects
					(font
						(size 1.27 1.27)
						(thickness 0.15)
					)
					(justify left bottom)
					(hide yes)
				)
			)
			(property "License" "Apache-2.0"
				(at 20.32 -22.86 0)
				(effects
					(font
						(size 1.27 1.27)
						(thickness 0.15)
					)
					(justify left bottom)
					(hide yes)
				)
			)
			(property "Author" "Antmicro"
				(at 20.32 -25.4 0)
				(effects
					(font
						(size 1.27 1.27)
						(thickness 0.15)
					)
					(justify left bottom)
					(hide yes)
				)
			)
			(property "Val" "1u"
				(at 20.32 -7.62 0)
				(effects
					(font
						(size 1.27 1.27)
						(thickness 0.15)
					)
					(justify left bottom)
				)
			)
			(property "Voltage" ""
				(at 20.32 -27.94 0)
				(effects
					(font
						(size 1.27 1.27)
					)
					(justify left bottom)
					(hide yes)
				)
			)
			(property "Dielectric" ""
				(at 20.32 -30.48 0)
				(effects
					(font
						(size 1.27 1.27)
					)
					(justify left bottom)
					(hide yes)
				)
			)
			(symbol "C_1u_0402_17_0_1"
				(polyline
					(pts
						(xy 2.032 -1.524) (xy 2.032 1.524)
					)
					(stroke
						(width 0.3048)
						(type default)
					)
					(fill
						(type none)
					)
				)
				(polyline
					(pts
						(xy 3.048 -1.524) (xy 3.048 1.524)
					)
					(stroke
						(width 0.3302)
						(type default)
					)
					(fill
						(type none)
					)
				)
			)
			(symbol "C_1u_0402_17_1_1"
				(pin passive line
					(at 0 0 0)
					(length 2.032)
					(name "~"
						(effects
							(font
								(size 1.27 1.27)
							)
						)
					)
					(number "1"
						(effects
							(font
								(size 1.27 1.27)
							)
						)
					)
				)
				(pin passive line
					(at 5.08 0 180)
					(length 2.032)
					(name "~"
						(effects
							(font
								(size 1.27 1.27)
							)
						)
					)
					(number "2"
						(effects
							(font
								(size 1.27 1.27)
							)
						)
					)
				)
			)
		)
	(symbol "thunderbolt-gpu-adapter:C_1u_0402_18"
			(pin_numbers hide)
			(pin_names hide)
			(exclude_from_sim no)
			(in_bom yes)
			(on_board yes)
			(property "Reference" "C"
				(at 20.32 -5.08 0)
				(effects
					(font
						(size 1.27 1.27)
						(thickness 0.15)
					)
					(justify left bottom)
				)
			)
			(property "Value" "C_1u_0402_18"
				(at 20.32 -10.16 0)
				(effects
					(font
						(size 1.27 1.27)
						(thickness 0.15)
					)
					(justify left bottom)
					(hide yes)
				)
			)
			(property "Footprint" "thunderbolt-gpu-adapter-footprints:C_0402_1005Metric"
				(at 20.32 -12.7 0)
				(effects
					(font
						(size 1.27 1.27)
						(thickness 0.15)
					)
					(justify left bottom)
					(hide yes)
				)
			)
			(property "Datasheet" " "
				(at 20.32 -15.24 0)
				(effects
					(font
						(size 1.27 1.27)
						(thickness 0.15)
					)
					(justify left bottom)
					(hide yes)
				)
			)
			(property "Description" " "
				(at 0 0 0)
				(effects
					(font
						(size 1.27 1.27)
					)
					(hide yes)
				)
			)
			(property "MPN" "C1005X6S1A105K050BC"
				(at 20.32 -17.78 0)
				(effects
					(font
						(size 1.27 1.27)
						(thickness 0.15)
					)
					(justify left bottom)
					(hide yes)
				)
			)
			(property "Manufacturer" "TDK"
				(at 20.32 -20.32 0)
				(effects
					(font
						(size 1.27 1.27)
						(thickness 0.15)
					)
					(justify left bottom)
					(hide yes)
				)
			)
			(property "License" "Apache-2.0"
				(at 20.32 -22.86 0)
				(effects
					(font
						(size 1.27 1.27)
						(thickness 0.15)
					)
					(justify left bottom)
					(hide yes)
				)
			)
			(property "Author" "Antmicro"
				(at 20.32 -25.4 0)
				(effects
					(font
						(size 1.27 1.27)
						(thickness 0.15)
					)
					(justify left bottom)
					(hide yes)
				)
			)
			(property "Val" "1u"
				(at 20.32 -7.62 0)
				(effects
					(font
						(size 1.27 1.27)
						(thickness 0.15)
					)
					(justify left bottom)
				)
			)
			(property "Voltage" ""
				(at 20.32 -27.94 0)
				(effects
					(font
						(size 1.27 1.27)
					)
					(justify left bottom)
					(hide yes)
				)
			)
			(property "Dielectric" ""
				(at 20.32 -30.48 0)
				(effects
					(font
						(size 1.27 1.27)
					)
					(justify left bottom)
					(hide yes)
				)
			)
			(symbol "C_1u_0402_18_0_1"
				(polyline
					(pts
						(xy 2.032 -1.524) (xy 2.032 1.524)
					)
					(stroke
						(width 0.3048)
						(type default)
					)
					(fill
						(type none)
					)
				)
				(polyline
					(pts
						(xy 3.048 -1.524) (xy 3.048 1.524)
					)
					(stroke
						(width 0.3302)
						(type default)
					)
					(fill
						(type none)
					)
				)
			)
			(symbol "C_1u_0402_18_1_1"
				(pin passive line
					(at 0 0 0)
					(length 2.032)
					(name "~"
						(effects
							(font
								(size 1.27 1.27)
							)
						)
					)
					(number "1"
						(effects
							(font
								(size 1.27 1.27)
							)
						)
					)
				)
				(pin passive line
					(at 5.08 0 180)
					(length 2.032)
					(name "~"
						(effects
							(font
								(size 1.27 1.27)
							)
						)
					)
					(number "2"
						(effects
							(font
								(size 1.27 1.27)
							)
						)
					)
				)
			)
		)
	(symbol "thunderbolt-gpu-adapter:C_1u_0402_19"
			(pin_numbers hide)
			(pin_names hide)
			(exclude_from_sim no)
			(in_bom yes)
			(on_board yes)
			(property "Reference" "C"
				(at 20.32 -5.08 0)
				(effects
					(font
						(size 1.27 1.27)
						(thickness 0.15)
					)
					(justify left bottom)
				)
			)
			(property "Value" "C_1u_0402_19"
				(at 20.32 -10.16 0)
				(effects
					(font
						(size 1.27 1.27)
						(thickness 0.15)
					)
					(justify left bottom)
					(hide yes)
				)
			)
			(property "Footprint" "thunderbolt-gpu-adapter-footprints:C_0402_1005Metric"
				(at 20.32 -12.7 0)
				(effects
					(font
						(size 1.27 1.27)
						(thickness 0.15)
					)
					(justify left bottom)
					(hide yes)
				)
			)
			(property "Datasheet" " "
				(at 20.32 -15.24 0)
				(effects
					(font
						(size 1.27 1.27)
						(thickness 0.15)
					)
					(justify left bottom)
					(hide yes)
				)
			)
			(property "Description" " "
				(at 0 0 0)
				(effects
					(font
						(size 1.27 1.27)
					)
					(hide yes)
				)
			)
			(property "MPN" "C1005X6S1A105K050BC"
				(at 20.32 -17.78 0)
				(effects
					(font
						(size 1.27 1.27)
						(thickness 0.15)
					)
					(justify left bottom)
					(hide yes)
				)
			)
			(property "Manufacturer" "TDK"
				(at 20.32 -20.32 0)
				(effects
					(font
						(size 1.27 1.27)
						(thickness 0.15)
					)
					(justify left bottom)
					(hide yes)
				)
			)
			(property "License" "Apache-2.0"
				(at 20.32 -22.86 0)
				(effects
					(font
						(size 1.27 1.27)
						(thickness 0.15)
					)
					(justify left bottom)
					(hide yes)
				)
			)
			(property "Author" "Antmicro"
				(at 20.32 -25.4 0)
				(effects
					(font
						(size 1.27 1.27)
						(thickness 0.15)
					)
					(justify left bottom)
					(hide yes)
				)
			)
			(property "Val" "1u"
				(at 20.32 -7.62 0)
				(effects
					(font
						(size 1.27 1.27)
						(thickness 0.15)
					)
					(justify left bottom)
				)
			)
			(property "Voltage" ""
				(at 20.32 -27.94 0)
				(effects
					(font
						(size 1.27 1.27)
					)
					(justify left bottom)
					(hide yes)
				)
			)
			(property "Dielectric" ""
				(at 20.32 -30.48 0)
				(effects
					(font
						(size 1.27 1.27)
					)
					(justify left bottom)
					(hide yes)
				)
			)
			(symbol "C_1u_0402_19_0_1"
				(polyline
					(pts
						(xy 2.032 -1.524) (xy 2.032 1.524)
					)
					(stroke
						(width 0.3048)
						(type default)
					)
					(fill
						(type none)
					)
				)
				(polyline
					(pts
						(xy 3.048 -1.524) (xy 3.048 1.524)
					)
					(stroke
						(width 0.3302)
						(type default)
					)
					(fill
						(type none)
					)
				)
			)
			(symbol "C_1u_0402_19_1_1"
				(pin passive line
					(at 0 0 0)
					(length 2.032)
					(name "~"
						(effects
							(font
								(size 1.27 1.27)
							)
						)
					)
					(number "1"
						(effects
							(font
								(size 1.27 1.27)
							)
						)
					)
				)
				(pin passive line
					(at 5.08 0 180)
					(length 2.032)
					(name "~"
						(effects
							(font
								(size 1.27 1.27)
							)
						)
					)
					(number "2"
						(effects
							(font
								(size 1.27 1.27)
							)
						)
					)
				)
			)
		)
	(symbol "thunderbolt-gpu-adapter:C_1u_0402_20"
			(pin_numbers hide)
			(pin_names hide)
			(exclude_from_sim no)
			(in_bom yes)
			(on_board yes)
			(property "Reference" "C"
				(at 20.32 -5.08 0)
				(effects
					(font
						(size 1.27 1.27)
						(thickness 0.15)
					)
					(justify left bottom)
				)
			)
			(property "Value" "C_1u_0402_20"
				(at 20.32 -10.16 0)
				(effects
					(font
						(size 1.27 1.27)
						(thickness 0.15)
					)
					(justify left bottom)
					(hide yes)
				)
			)
			(property "Footprint" "thunderbolt-gpu-adapter-footprints:C_0402_1005Metric"
				(at 20.32 -12.7 0)
				(effects
					(font
						(size 1.27 1.27)
						(thickness 0.15)
					)
					(justify left bottom)
					(hide yes)
				)
			)
			(property "Datasheet" " "
				(at 20.32 -15.24 0)
				(effects
					(font
						(size 1.27 1.27)
						(thickness 0.15)
					)
					(justify left bottom)
					(hide yes)
				)
			)
			(property "Description" " "
				(at 0 0 0)
				(effects
					(font
						(size 1.27 1.27)
					)
					(hide yes)
				)
			)
			(property "MPN" "C1005X6S1A105K050BC"
				(at 20.32 -17.78 0)
				(effects
					(font
						(size 1.27 1.27)
						(thickness 0.15)
					)
					(justify left bottom)
					(hide yes)
				)
			)
			(property "Manufacturer" "TDK"
				(at 20.32 -20.32 0)
				(effects
					(font
						(size 1.27 1.27)
						(thickness 0.15)
					)
					(justify left bottom)
					(hide yes)
				)
			)
			(property "License" "Apache-2.0"
				(at 20.32 -22.86 0)
				(effects
					(font
						(size 1.27 1.27)
						(thickness 0.15)
					)
					(justify left bottom)
					(hide yes)
				)
			)
			(property "Author" "Antmicro"
				(at 20.32 -25.4 0)
				(effects
					(font
						(size 1.27 1.27)
						(thickness 0.15)
					)
					(justify left bottom)
					(hide yes)
				)
			)
			(property "Val" "1u"
				(at 20.32 -7.62 0)
				(effects
					(font
						(size 1.27 1.27)
						(thickness 0.15)
					)
					(justify left bottom)
				)
			)
			(property "Voltage" ""
				(at 20.32 -27.94 0)
				(effects
					(font
						(size 1.27 1.27)
					)
					(justify left bottom)
					(hide yes)
				)
			)
			(property "Dielectric" ""
				(at 20.32 -30.48 0)
				(effects
					(font
						(size 1.27 1.27)
					)
					(justify left bottom)
					(hide yes)
				)
			)
			(symbol "C_1u_0402_20_0_1"
				(polyline
					(pts
						(xy 2.032 -1.524) (xy 2.032 1.524)
					)
					(stroke
						(width 0.3048)
						(type default)
					)
					(fill
						(type none)
					)
				)
				(polyline
					(pts
						(xy 3.048 -1.524) (xy 3.048 1.524)
					)
					(stroke
						(width 0.3302)
						(type default)
					)
					(fill
						(type none)
					)
				)
			)
			(symbol "C_1u_0402_20_1_1"
				(pin passive line
					(at 0 0 0)
					(length 2.032)
					(name "~"
						(effects
							(font
								(size 1.27 1.27)
							)
						)
					)
					(number "1"
						(effects
							(font
								(size 1.27 1.27)
							)
						)
					)
				)
				(pin passive line
					(at 5.08 0 180)
					(length 2.032)
					(name "~"
						(effects
							(font
								(size 1.27 1.27)
							)
						)
					)
					(number "2"
						(effects
							(font
								(size 1.27 1.27)
							)
						)
					)
				)
			)
		)
	(symbol "thunderbolt-gpu-adapter:C_1u_0402_21"
			(pin_numbers hide)
			(pin_names hide)
			(exclude_from_sim no)
			(in_bom yes)
			(on_board yes)
			(property "Reference" "C"
				(at 20.32 -5.08 0)
				(effects
					(font
						(size 1.27 1.27)
						(thickness 0.15)
					)
					(justify left bottom)
				)
			)
			(property "Value" "C_1u_0402_21"
				(at 20.32 -10.16 0)
				(effects
					(font
						(size 1.27 1.27)
						(thickness 0.15)
					)
					(justify left bottom)
					(hide yes)
				)
			)
			(property "Footprint" "thunderbolt-gpu-adapter-footprints:C_0402_1005Metric"
				(at 20.32 -12.7 0)
				(effects
					(font
						(size 1.27 1.27)
						(thickness 0.15)
					)
					(justify left bottom)
					(hide yes)
				)
			)
			(property "Datasheet" " "
				(at 20.32 -15.24 0)
				(effects
					(font
						(size 1.27 1.27)
						(thickness 0.15)
					)
					(justify left bottom)
					(hide yes)
				)
			)
			(property "Description" " "
				(at 0 0 0)
				(effects
					(font
						(size 1.27 1.27)
					)
					(hide yes)
				)
			)
			(property "MPN" "C1005X6S1A105K050BC"
				(at 20.32 -17.78 0)
				(effects
					(font
						(size 1.27 1.27)
						(thickness 0.15)
					)
					(justify left bottom)
					(hide yes)
				)
			)
			(property "Manufacturer" "TDK"
				(at 20.32 -20.32 0)
				(effects
					(font
						(size 1.27 1.27)
						(thickness 0.15)
					)
					(justify left bottom)
					(hide yes)
				)
			)
			(property "License" "Apache-2.0"
				(at 20.32 -22.86 0)
				(effects
					(font
						(size 1.27 1.27)
						(thickness 0.15)
					)
					(justify left bottom)
					(hide yes)
				)
			)
			(property "Author" "Antmicro"
				(at 20.32 -25.4 0)
				(effects
					(font
						(size 1.27 1.27)
						(thickness 0.15)
					)
					(justify left bottom)
					(hide yes)
				)
			)
			(property "Val" "1u"
				(at 20.32 -7.62 0)
				(effects
					(font
						(size 1.27 1.27)
						(thickness 0.15)
					)
					(justify left bottom)
				)
			)
			(property "Voltage" ""
				(at 20.32 -27.94 0)
				(effects
					(font
						(size 1.27 1.27)
					)
					(justify left bottom)
					(hide yes)
				)
			)
			(property "Dielectric" ""
				(at 20.32 -30.48 0)
				(effects
					(font
						(size 1.27 1.27)
					)
					(justify left bottom)
					(hide yes)
				)
			)
			(symbol "C_1u_0402_21_0_1"
				(polyline
					(pts
						(xy 2.032 -1.524) (xy 2.032 1.524)
					)
					(stroke
						(width 0.3048)
						(type default)
					)
					(fill
						(type none)
					)
				)
				(polyline
					(pts
						(xy 3.048 -1.524) (xy 3.048 1.524)
					)
					(stroke
						(width 0.3302)
						(type default)
					)
					(fill
						(type none)
					)
				)
			)
			(symbol "C_1u_0402_21_1_1"
				(pin passive line
					(at 0 0 0)
					(length 2.032)
					(name "~"
						(effects
							(font
								(size 1.27 1.27)
							)
						)
					)
					(number "1"
						(effects
							(font
								(size 1.27 1.27)
							)
						)
					)
				)
				(pin passive line
					(at 5.08 0 180)
					(length 2.032)
					(name "~"
						(effects
							(font
								(size 1.27 1.27)
							)
						)
					)
					(number "2"
						(effects
							(font
								(size 1.27 1.27)
							)
						)
					)
				)
			)
		)
	(symbol "thunderbolt-gpu-adapter:C_1u_0402_22"
			(pin_numbers hide)
			(pin_names hide)
			(exclude_from_sim no)
			(in_bom yes)
			(on_board yes)
			(property "Reference" "C"
				(at 20.32 -5.08 0)
				(effects
					(font
						(size 1.27 1.27)
						(thickness 0.15)
					)
					(justify left bottom)
				)
			)
			(property "Value" "C_1u_0402_22"
				(at 20.32 -10.16 0)
				(effects
					(font
						(size 1.27 1.27)
						(thickness 0.15)
					)
					(justify left bottom)
					(hide yes)
				)
			)
			(property "Footprint" "thunderbolt-gpu-adapter-footprints:C_0402_1005Metric"
				(at 20.32 -12.7 0)
				(effects
					(font
						(size 1.27 1.27)
						(thickness 0.15)
					)
					(justify left bottom)
					(hide yes)
				)
			)
			(property "Datasheet" " "
				(at 20.32 -15.24 0)
				(effects
					(font
						(size 1.27 1.27)
						(thickness 0.15)
					)
					(justify left bottom)
					(hide yes)
				)
			)
			(property "Description" " "
				(at 0 0 0)
				(effects
					(font
						(size 1.27 1.27)
					)
					(hide yes)
				)
			)
			(property "MPN" "C1005X6S1A105K050BC"
				(at 20.32 -17.78 0)
				(effects
					(font
						(size 1.27 1.27)
						(thickness 0.15)
					)
					(justify left bottom)
					(hide yes)
				)
			)
			(property "Manufacturer" "TDK"
				(at 20.32 -20.32 0)
				(effects
					(font
						(size 1.27 1.27)
						(thickness 0.15)
					)
					(justify left bottom)
					(hide yes)
				)
			)
			(property "License" "Apache-2.0"
				(at 20.32 -22.86 0)
				(effects
					(font
						(size 1.27 1.27)
						(thickness 0.15)
					)
					(justify left bottom)
					(hide yes)
				)
			)
			(property "Author" "Antmicro"
				(at 20.32 -25.4 0)
				(effects
					(font
						(size 1.27 1.27)
						(thickness 0.15)
					)
					(justify left bottom)
					(hide yes)
				)
			)
			(property "Val" "1u"
				(at 20.32 -7.62 0)
				(effects
					(font
						(size 1.27 1.27)
						(thickness 0.15)
					)
					(justify left bottom)
				)
			)
			(property "Voltage" ""
				(at 20.32 -27.94 0)
				(effects
					(font
						(size 1.27 1.27)
					)
					(justify left bottom)
					(hide yes)
				)
			)
			(property "Dielectric" ""
				(at 20.32 -30.48 0)
				(effects
					(font
						(size 1.27 1.27)
					)
					(justify left bottom)
					(hide yes)
				)
			)
			(symbol "C_1u_0402_22_0_1"
				(polyline
					(pts
						(xy 2.032 -1.524) (xy 2.032 1.524)
					)
					(stroke
						(width 0.3048)
						(type default)
					)
					(fill
						(type none)
					)
				)
				(polyline
					(pts
						(xy 3.048 -1.524) (xy 3.048 1.524)
					)
					(stroke
						(width 0.3302)
						(type default)
					)
					(fill
						(type none)
					)
				)
			)
			(symbol "C_1u_0402_22_1_1"
				(pin passive line
					(at 0 0 0)
					(length 2.032)
					(name "~"
						(effects
							(font
								(size 1.27 1.27)
							)
						)
					)
					(number "1"
						(effects
							(font
								(size 1.27 1.27)
							)
						)
					)
				)
				(pin passive line
					(at 5.08 0 180)
					(length 2.032)
					(name "~"
						(effects
							(font
								(size 1.27 1.27)
							)
						)
					)
					(number "2"
						(effects
							(font
								(size 1.27 1.27)
							)
						)
					)
				)
			)
		)
	(symbol "thunderbolt-gpu-adapter:C_1u_0402_23"
			(pin_numbers hide)
			(pin_names hide)
			(exclude_from_sim no)
			(in_bom yes)
			(on_board yes)
			(property "Reference" "C"
				(at 20.32 -5.08 0)
				(effects
					(font
						(size 1.27 1.27)
						(thickness 0.15)
					)
					(justify left bottom)
				)
			)
			(property "Value" "C_1u_0402_23"
				(at 20.32 -10.16 0)
				(effects
					(font
						(size 1.27 1.27)
						(thickness 0.15)
					)
					(justify left bottom)
					(hide yes)
				)
			)
			(property "Footprint" "thunderbolt-gpu-adapter-footprints:C_0402_1005Metric"
				(at 20.32 -12.7 0)
				(effects
					(font
						(size 1.27 1.27)
						(thickness 0.15)
					)
					(justify left bottom)
					(hide yes)
				)
			)
			(property "Datasheet" " "
				(at 20.32 -15.24 0)
				(effects
					(font
						(size 1.27 1.27)
						(thickness 0.15)
					)
					(justify left bottom)
					(hide yes)
				)
			)
			(property "Description" " "
				(at 0 0 0)
				(effects
					(font
						(size 1.27 1.27)
					)
					(hide yes)
				)
			)
			(property "MPN" "C1005X6S1A105K050BC"
				(at 20.32 -17.78 0)
				(effects
					(font
						(size 1.27 1.27)
						(thickness 0.15)
					)
					(justify left bottom)
					(hide yes)
				)
			)
			(property "Manufacturer" "TDK"
				(at 20.32 -20.32 0)
				(effects
					(font
						(size 1.27 1.27)
						(thickness 0.15)
					)
					(justify left bottom)
					(hide yes)
				)
			)
			(property "License" "Apache-2.0"
				(at 20.32 -22.86 0)
				(effects
					(font
						(size 1.27 1.27)
						(thickness 0.15)
					)
					(justify left bottom)
					(hide yes)
				)
			)
			(property "Author" "Antmicro"
				(at 20.32 -25.4 0)
				(effects
					(font
						(size 1.27 1.27)
						(thickness 0.15)
					)
					(justify left bottom)
					(hide yes)
				)
			)
			(property "Val" "1u"
				(at 20.32 -7.62 0)
				(effects
					(font
						(size 1.27 1.27)
						(thickness 0.15)
					)
					(justify left bottom)
				)
			)
			(property "Voltage" ""
				(at 20.32 -27.94 0)
				(effects
					(font
						(size 1.27 1.27)
					)
					(justify left bottom)
					(hide yes)
				)
			)
			(property "Dielectric" ""
				(at 20.32 -30.48 0)
				(effects
					(font
						(size 1.27 1.27)
					)
					(justify left bottom)
					(hide yes)
				)
			)
			(symbol "C_1u_0402_23_0_1"
				(polyline
					(pts
						(xy 2.032 -1.524) (xy 2.032 1.524)
					)
					(stroke
						(width 0.3048)
						(type default)
					)
					(fill
						(type none)
					)
				)
				(polyline
					(pts
						(xy 3.048 -1.524) (xy 3.048 1.524)
					)
					(stroke
						(width 0.3302)
						(type default)
					)
					(fill
						(type none)
					)
				)
			)
			(symbol "C_1u_0402_23_1_1"
				(pin passive line
					(at 0 0 0)
					(length 2.032)
					(name "~"
						(effects
							(font
								(size 1.27 1.27)
							)
						)
					)
					(number "1"
						(effects
							(font
								(size 1.27 1.27)
							)
						)
					)
				)
				(pin passive line
					(at 5.08 0 180)
					(length 2.032)
					(name "~"
						(effects
							(font
								(size 1.27 1.27)
							)
						)
					)
					(number "2"
						(effects
							(font
								(size 1.27 1.27)
							)
						)
					)
				)
			)
		)
	(symbol "thunderbolt-gpu-adapter:C_1u_0402_24"
			(pin_numbers hide)
			(pin_names hide)
			(exclude_from_sim no)
			(in_bom yes)
			(on_board yes)
			(property "Reference" "C"
				(at 20.32 -5.08 0)
				(effects
					(font
						(size 1.27 1.27)
						(thickness 0.15)
					)
					(justify left bottom)
				)
			)
			(property "Value" "C_1u_0402_24"
				(at 20.32 -10.16 0)
				(effects
					(font
						(size 1.27 1.27)
						(thickness 0.15)
					)
					(justify left bottom)
					(hide yes)
				)
			)
			(property "Footprint" "thunderbolt-gpu-adapter-footprints:C_0402_1005Metric"
				(at 20.32 -12.7 0)
				(effects
					(font
						(size 1.27 1.27)
						(thickness 0.15)
					)
					(justify left bottom)
					(hide yes)
				)
			)
			(property "Datasheet" " "
				(at 20.32 -15.24 0)
				(effects
					(font
						(size 1.27 1.27)
						(thickness 0.15)
					)
					(justify left bottom)
					(hide yes)
				)
			)
			(property "Description" " "
				(at 0 0 0)
				(effects
					(font
						(size 1.27 1.27)
					)
					(hide yes)
				)
			)
			(property "MPN" "C1005X6S1A105K050BC"
				(at 20.32 -17.78 0)
				(effects
					(font
						(size 1.27 1.27)
						(thickness 0.15)
					)
					(justify left bottom)
					(hide yes)
				)
			)
			(property "Manufacturer" "TDK"
				(at 20.32 -20.32 0)
				(effects
					(font
						(size 1.27 1.27)
						(thickness 0.15)
					)
					(justify left bottom)
					(hide yes)
				)
			)
			(property "License" "Apache-2.0"
				(at 20.32 -22.86 0)
				(effects
					(font
						(size 1.27 1.27)
						(thickness 0.15)
					)
					(justify left bottom)
					(hide yes)
				)
			)
			(property "Author" "Antmicro"
				(at 20.32 -25.4 0)
				(effects
					(font
						(size 1.27 1.27)
						(thickness 0.15)
					)
					(justify left bottom)
					(hide yes)
				)
			)
			(property "Val" "1u"
				(at 20.32 -7.62 0)
				(effects
					(font
						(size 1.27 1.27)
						(thickness 0.15)
					)
					(justify left bottom)
				)
			)
			(property "Voltage" ""
				(at 20.32 -27.94 0)
				(effects
					(font
						(size 1.27 1.27)
					)
					(justify left bottom)
					(hide yes)
				)
			)
			(property "Dielectric" ""
				(at 20.32 -30.48 0)
				(effects
					(font
						(size 1.27 1.27)
					)
					(justify left bottom)
					(hide yes)
				)
			)
			(symbol "C_1u_0402_24_0_1"
				(polyline
					(pts
						(xy 2.032 -1.524) (xy 2.032 1.524)
					)
					(stroke
						(width 0.3048)
						(type default)
					)
					(fill
						(type none)
					)
				)
				(polyline
					(pts
						(xy 3.048 -1.524) (xy 3.048 1.524)
					)
					(stroke
						(width 0.3302)
						(type default)
					)
					(fill
						(type none)
					)
				)
			)
			(symbol "C_1u_0402_24_1_1"
				(pin passive line
					(at 0 0 0)
					(length 2.032)
					(name "~"
						(effects
							(font
								(size 1.27 1.27)
							)
						)
					)
					(number "1"
						(effects
							(font
								(size 1.27 1.27)
							)
						)
					)
				)
				(pin passive line
					(at 5.08 0 180)
					(length 2.032)
					(name "~"
						(effects
							(font
								(size 1.27 1.27)
							)
						)
					)
					(number "2"
						(effects
							(font
								(size 1.27 1.27)
							)
						)
					)
				)
			)
		)
	(symbol "thunderbolt-gpu-adapter:C_1u_0402_25"
			(pin_numbers hide)
			(pin_names hide)
			(exclude_from_sim no)
			(in_bom yes)
			(on_board yes)
			(property "Reference" "C"
				(at 20.32 -5.08 0)
				(effects
					(font
						(size 1.27 1.27)
						(thickness 0.15)
					)
					(justify left bottom)
				)
			)
			(property "Value" "C_1u_0402_25"
				(at 20.32 -10.16 0)
				(effects
					(font
						(size 1.27 1.27)
						(thickness 0.15)
					)
					(justify left bottom)
					(hide yes)
				)
			)
			(property "Footprint" "thunderbolt-gpu-adapter-footprints:C_0402_1005Metric"
				(at 20.32 -12.7 0)
				(effects
					(font
						(size 1.27 1.27)
						(thickness 0.15)
					)
					(justify left bottom)
					(hide yes)
				)
			)
			(property "Datasheet" " "
				(at 20.32 -15.24 0)
				(effects
					(font
						(size 1.27 1.27)
						(thickness 0.15)
					)
					(justify left bottom)
					(hide yes)
				)
			)
			(property "Description" " "
				(at 0 0 0)
				(effects
					(font
						(size 1.27 1.27)
					)
					(hide yes)
				)
			)
			(property "MPN" "C1005X6S1A105K050BC"
				(at 20.32 -17.78 0)
				(effects
					(font
						(size 1.27 1.27)
						(thickness 0.15)
					)
					(justify left bottom)
					(hide yes)
				)
			)
			(property "Manufacturer" "TDK"
				(at 20.32 -20.32 0)
				(effects
					(font
						(size 1.27 1.27)
						(thickness 0.15)
					)
					(justify left bottom)
					(hide yes)
				)
			)
			(property "License" "Apache-2.0"
				(at 20.32 -22.86 0)
				(effects
					(font
						(size 1.27 1.27)
						(thickness 0.15)
					)
					(justify left bottom)
					(hide yes)
				)
			)
			(property "Author" "Antmicro"
				(at 20.32 -25.4 0)
				(effects
					(font
						(size 1.27 1.27)
						(thickness 0.15)
					)
					(justify left bottom)
					(hide yes)
				)
			)
			(property "Val" "1u"
				(at 20.32 -7.62 0)
				(effects
					(font
						(size 1.27 1.27)
						(thickness 0.15)
					)
					(justify left bottom)
				)
			)
			(property "Voltage" ""
				(at 20.32 -27.94 0)
				(effects
					(font
						(size 1.27 1.27)
					)
					(justify left bottom)
					(hide yes)
				)
			)
			(property "Dielectric" ""
				(at 20.32 -30.48 0)
				(effects
					(font
						(size 1.27 1.27)
					)
					(justify left bottom)
					(hide yes)
				)
			)
			(symbol "C_1u_0402_25_0_1"
				(polyline
					(pts
						(xy 2.032 -1.524) (xy 2.032 1.524)
					)
					(stroke
						(width 0.3048)
						(type default)
					)
					(fill
						(type none)
					)
				)
				(polyline
					(pts
						(xy 3.048 -1.524) (xy 3.048 1.524)
					)
					(stroke
						(width 0.3302)
						(type default)
					)
					(fill
						(type none)
					)
				)
			)
			(symbol "C_1u_0402_25_1_1"
				(pin passive line
					(at 0 0 0)
					(length 2.032)
					(name "~"
						(effects
							(font
								(size 1.27 1.27)
							)
						)
					)
					(number "1"
						(effects
							(font
								(size 1.27 1.27)
							)
						)
					)
				)
				(pin passive line
					(at 5.08 0 180)
					(length 2.032)
					(name "~"
						(effects
							(font
								(size 1.27 1.27)
							)
						)
					)
					(number "2"
						(effects
							(font
								(size 1.27 1.27)
							)
						)
					)
				)
			)
		)
	(symbol "thunderbolt-gpu-adapter:C_1u_0402_26"
			(pin_numbers hide)
			(pin_names hide)
			(exclude_from_sim no)
			(in_bom yes)
			(on_board yes)
			(property "Reference" "C"
				(at 20.32 -5.08 0)
				(effects
					(font
						(size 1.27 1.27)
						(thickness 0.15)
					)
					(justify left bottom)
				)
			)
			(property "Value" "C_1u_0402_26"
				(at 20.32 -10.16 0)
				(effects
					(font
						(size 1.27 1.27)
						(thickness 0.15)
					)
					(justify left bottom)
					(hide yes)
				)
			)
			(property "Footprint" "thunderbolt-gpu-adapter-footprints:C_0402_1005Metric"
				(at 20.32 -12.7 0)
				(effects
					(font
						(size 1.27 1.27)
						(thickness 0.15)
					)
					(justify left bottom)
					(hide yes)
				)
			)
			(property "Datasheet" " "
				(at 20.32 -15.24 0)
				(effects
					(font
						(size 1.27 1.27)
						(thickness 0.15)
					)
					(justify left bottom)
					(hide yes)
				)
			)
			(property "Description" " "
				(at 0 0 0)
				(effects
					(font
						(size 1.27 1.27)
					)
					(hide yes)
				)
			)
			(property "MPN" "C1005X6S1A105K050BC"
				(at 20.32 -17.78 0)
				(effects
					(font
						(size 1.27 1.27)
						(thickness 0.15)
					)
					(justify left bottom)
					(hide yes)
				)
			)
			(property "Manufacturer" "TDK"
				(at 20.32 -20.32 0)
				(effects
					(font
						(size 1.27 1.27)
						(thickness 0.15)
					)
					(justify left bottom)
					(hide yes)
				)
			)
			(property "License" "Apache-2.0"
				(at 20.32 -22.86 0)
				(effects
					(font
						(size 1.27 1.27)
						(thickness 0.15)
					)
					(justify left bottom)
					(hide yes)
				)
			)
			(property "Author" "Antmicro"
				(at 20.32 -25.4 0)
				(effects
					(font
						(size 1.27 1.27)
						(thickness 0.15)
					)
					(justify left bottom)
					(hide yes)
				)
			)
			(property "Val" "1u"
				(at 20.32 -7.62 0)
				(effects
					(font
						(size 1.27 1.27)
						(thickness 0.15)
					)
					(justify left bottom)
				)
			)
			(property "Voltage" ""
				(at 20.32 -27.94 0)
				(effects
					(font
						(size 1.27 1.27)
					)
					(justify left bottom)
					(hide yes)
				)
			)
			(property "Dielectric" ""
				(at 20.32 -30.48 0)
				(effects
					(font
						(size 1.27 1.27)
					)
					(justify left bottom)
					(hide yes)
				)
			)
			(symbol "C_1u_0402_26_0_1"
				(polyline
					(pts
						(xy 2.032 -1.524) (xy 2.032 1.524)
					)
					(stroke
						(width 0.3048)
						(type default)
					)
					(fill
						(type none)
					)
				)
				(polyline
					(pts
						(xy 3.048 -1.524) (xy 3.048 1.524)
					)
					(stroke
						(width 0.3302)
						(type default)
					)
					(fill
						(type none)
					)
				)
			)
			(symbol "C_1u_0402_26_1_1"
				(pin passive line
					(at 0 0 0)
					(length 2.032)
					(name "~"
						(effects
							(font
								(size 1.27 1.27)
							)
						)
					)
					(number "1"
						(effects
							(font
								(size 1.27 1.27)
							)
						)
					)
				)
				(pin passive line
					(at 5.08 0 180)
					(length 2.032)
					(name "~"
						(effects
							(font
								(size 1.27 1.27)
							)
						)
					)
					(number "2"
						(effects
							(font
								(size 1.27 1.27)
							)
						)
					)
				)
			)
		)
	(symbol "thunderbolt-gpu-adapter:C_1u_0402_27"
			(pin_numbers hide)
			(pin_names hide)
			(exclude_from_sim no)
			(in_bom yes)
			(on_board yes)
			(property "Reference" "C"
				(at 20.32 -5.08 0)
				(effects
					(font
						(size 1.27 1.27)
						(thickness 0.15)
					)
					(justify left bottom)
				)
			)
			(property "Value" "C_1u_0402_27"
				(at 20.32 -10.16 0)
				(effects
					(font
						(size 1.27 1.27)
						(thickness 0.15)
					)
					(justify left bottom)
					(hide yes)
				)
			)
			(property "Footprint" "thunderbolt-gpu-adapter-footprints:C_0402_1005Metric"
				(at 20.32 -12.7 0)
				(effects
					(font
						(size 1.27 1.27)
						(thickness 0.15)
					)
					(justify left bottom)
					(hide yes)
				)
			)
			(property "Datasheet" " "
				(at 20.32 -15.24 0)
				(effects
					(font
						(size 1.27 1.27)
						(thickness 0.15)
					)
					(justify left bottom)
					(hide yes)
				)
			)
			(property "Description" " "
				(at 0 0 0)
				(effects
					(font
						(size 1.27 1.27)
					)
					(hide yes)
				)
			)
			(property "MPN" "C1005X6S1A105K050BC"
				(at 20.32 -17.78 0)
				(effects
					(font
						(size 1.27 1.27)
						(thickness 0.15)
					)
					(justify left bottom)
					(hide yes)
				)
			)
			(property "Manufacturer" "TDK"
				(at 20.32 -20.32 0)
				(effects
					(font
						(size 1.27 1.27)
						(thickness 0.15)
					)
					(justify left bottom)
					(hide yes)
				)
			)
			(property "License" "Apache-2.0"
				(at 20.32 -22.86 0)
				(effects
					(font
						(size 1.27 1.27)
						(thickness 0.15)
					)
					(justify left bottom)
					(hide yes)
				)
			)
			(property "Author" "Antmicro"
				(at 20.32 -25.4 0)
				(effects
					(font
						(size 1.27 1.27)
						(thickness 0.15)
					)
					(justify left bottom)
					(hide yes)
				)
			)
			(property "Val" "1u"
				(at 20.32 -7.62 0)
				(effects
					(font
						(size 1.27 1.27)
						(thickness 0.15)
					)
					(justify left bottom)
				)
			)
			(property "Voltage" ""
				(at 20.32 -27.94 0)
				(effects
					(font
						(size 1.27 1.27)
					)
					(justify left bottom)
					(hide yes)
				)
			)
			(property "Dielectric" ""
				(at 20.32 -30.48 0)
				(effects
					(font
						(size 1.27 1.27)
					)
					(justify left bottom)
					(hide yes)
				)
			)
			(symbol "C_1u_0402_27_0_1"
				(polyline
					(pts
						(xy 2.032 -1.524) (xy 2.032 1.524)
					)
					(stroke
						(width 0.3048)
						(type default)
					)
					(fill
						(type none)
					)
				)
				(polyline
					(pts
						(xy 3.048 -1.524) (xy 3.048 1.524)
					)
					(stroke
						(width 0.3302)
						(type default)
					)
					(fill
						(type none)
					)
				)
			)
			(symbol "C_1u_0402_27_1_1"
				(pin passive line
					(at 0 0 0)
					(length 2.032)
					(name "~"
						(effects
							(font
								(size 1.27 1.27)
							)
						)
					)
					(number "1"
						(effects
							(font
								(size 1.27 1.27)
							)
						)
					)
				)
				(pin passive line
					(at 5.08 0 180)
					(length 2.032)
					(name "~"
						(effects
							(font
								(size 1.27 1.27)
							)
						)
					)
					(number "2"
						(effects
							(font
								(size 1.27 1.27)
							)
						)
					)
				)
			)
		)
	(symbol "thunderbolt-gpu-adapter:C_1u_0402_28"
			(pin_numbers hide)
			(pin_names hide)
			(exclude_from_sim no)
			(in_bom yes)
			(on_board yes)
			(property "Reference" "C"
				(at 20.32 -5.08 0)
				(effects
					(font
						(size 1.27 1.27)
						(thickness 0.15)
					)
					(justify left bottom)
				)
			)
			(property "Value" "C_1u_0402_28"
				(at 20.32 -10.16 0)
				(effects
					(font
						(size 1.27 1.27)
						(thickness 0.15)
					)
					(justify left bottom)
					(hide yes)
				)
			)
			(property "Footprint" "thunderbolt-gpu-adapter-footprints:C_0402_1005Metric"
				(at 20.32 -12.7 0)
				(effects
					(font
						(size 1.27 1.27)
						(thickness 0.15)
					)
					(justify left bottom)
					(hide yes)
				)
			)
			(property "Datasheet" " "
				(at 20.32 -15.24 0)
				(effects
					(font
						(size 1.27 1.27)
						(thickness 0.15)
					)
					(justify left bottom)
					(hide yes)
				)
			)
			(property "Description" " "
				(at 0 0 0)
				(effects
					(font
						(size 1.27 1.27)
					)
					(hide yes)
				)
			)
			(property "MPN" "C1005X6S1A105K050BC"
				(at 20.32 -17.78 0)
				(effects
					(font
						(size 1.27 1.27)
						(thickness 0.15)
					)
					(justify left bottom)
					(hide yes)
				)
			)
			(property "Manufacturer" "TDK"
				(at 20.32 -20.32 0)
				(effects
					(font
						(size 1.27 1.27)
						(thickness 0.15)
					)
					(justify left bottom)
					(hide yes)
				)
			)
			(property "License" "Apache-2.0"
				(at 20.32 -22.86 0)
				(effects
					(font
						(size 1.27 1.27)
						(thickness 0.15)
					)
					(justify left bottom)
					(hide yes)
				)
			)
			(property "Author" "Antmicro"
				(at 20.32 -25.4 0)
				(effects
					(font
						(size 1.27 1.27)
						(thickness 0.15)
					)
					(justify left bottom)
					(hide yes)
				)
			)
			(property "Val" "1u"
				(at 20.32 -7.62 0)
				(effects
					(font
						(size 1.27 1.27)
						(thickness 0.15)
					)
					(justify left bottom)
				)
			)
			(property "Voltage" ""
				(at 20.32 -27.94 0)
				(effects
					(font
						(size 1.27 1.27)
					)
					(justify left bottom)
					(hide yes)
				)
			)
			(property "Dielectric" ""
				(at 20.32 -30.48 0)
				(effects
					(font
						(size 1.27 1.27)
					)
					(justify left bottom)
					(hide yes)
				)
			)
			(symbol "C_1u_0402_28_0_1"
				(polyline
					(pts
						(xy 2.032 -1.524) (xy 2.032 1.524)
					)
					(stroke
						(width 0.3048)
						(type default)
					)
					(fill
						(type none)
					)
				)
				(polyline
					(pts
						(xy 3.048 -1.524) (xy 3.048 1.524)
					)
					(stroke
						(width 0.3302)
						(type default)
					)
					(fill
						(type none)
					)
				)
			)
			(symbol "C_1u_0402_28_1_1"
				(pin passive line
					(at 0 0 0)
					(length 2.032)
					(name "~"
						(effects
							(font
								(size 1.27 1.27)
							)
						)
					)
					(number "1"
						(effects
							(font
								(size 1.27 1.27)
							)
						)
					)
				)
				(pin passive line
					(at 5.08 0 180)
					(length 2.032)
					(name "~"
						(effects
							(font
								(size 1.27 1.27)
							)
						)
					)
					(number "2"
						(effects
							(font
								(size 1.27 1.27)
							)
						)
					)
				)
			)
		)
	(symbol "thunderbolt-gpu-adapter:C_1u_0402_29"
			(pin_numbers hide)
			(pin_names hide)
			(exclude_from_sim no)
			(in_bom yes)
			(on_board yes)
			(property "Reference" "C"
				(at 20.32 -5.08 0)
				(effects
					(font
						(size 1.27 1.27)
						(thickness 0.15)
					)
					(justify left bottom)
				)
			)
			(property "Value" "C_1u_0402_29"
				(at 20.32 -10.16 0)
				(effects
					(font
						(size 1.27 1.27)
						(thickness 0.15)
					)
					(justify left bottom)
					(hide yes)
				)
			)
			(property "Footprint" "thunderbolt-gpu-adapter-footprints:C_0402_1005Metric"
				(at 20.32 -12.7 0)
				(effects
					(font
						(size 1.27 1.27)
						(thickness 0.15)
					)
					(justify left bottom)
					(hide yes)
				)
			)
			(property "Datasheet" " "
				(at 20.32 -15.24 0)
				(effects
					(font
						(size 1.27 1.27)
						(thickness 0.15)
					)
					(justify left bottom)
					(hide yes)
				)
			)
			(property "Description" " "
				(at 0 0 0)
				(effects
					(font
						(size 1.27 1.27)
					)
					(hide yes)
				)
			)
			(property "MPN" "C1005X6S1A105K050BC"
				(at 20.32 -17.78 0)
				(effects
					(font
						(size 1.27 1.27)
						(thickness 0.15)
					)
					(justify left bottom)
					(hide yes)
				)
			)
			(property "Manufacturer" "TDK"
				(at 20.32 -20.32 0)
				(effects
					(font
						(size 1.27 1.27)
						(thickness 0.15)
					)
					(justify left bottom)
					(hide yes)
				)
			)
			(property "License" "Apache-2.0"
				(at 20.32 -22.86 0)
				(effects
					(font
						(size 1.27 1.27)
						(thickness 0.15)
					)
					(justify left bottom)
					(hide yes)
				)
			)
			(property "Author" "Antmicro"
				(at 20.32 -25.4 0)
				(effects
					(font
						(size 1.27 1.27)
						(thickness 0.15)
					)
					(justify left bottom)
					(hide yes)
				)
			)
			(property "Val" "1u"
				(at 20.32 -7.62 0)
				(effects
					(font
						(size 1.27 1.27)
						(thickness 0.15)
					)
					(justify left bottom)
				)
			)
			(property "Voltage" ""
				(at 20.32 -27.94 0)
				(effects
					(font
						(size 1.27 1.27)
					)
					(justify left bottom)
					(hide yes)
				)
			)
			(property "Dielectric" ""
				(at 20.32 -30.48 0)
				(effects
					(font
						(size 1.27 1.27)
					)
					(justify left bottom)
					(hide yes)
				)
			)
			(symbol "C_1u_0402_29_0_1"
				(polyline
					(pts
						(xy 2.032 -1.524) (xy 2.032 1.524)
					)
					(stroke
						(width 0.3048)
						(type default)
					)
					(fill
						(type none)
					)
				)
				(polyline
					(pts
						(xy 3.048 -1.524) (xy 3.048 1.524)
					)
					(stroke
						(width 0.3302)
						(type default)
					)
					(fill
						(type none)
					)
				)
			)
			(symbol "C_1u_0402_29_1_1"
				(pin passive line
					(at 0 0 0)
					(length 2.032)
					(name "~"
						(effects
							(font
								(size 1.27 1.27)
							)
						)
					)
					(number "1"
						(effects
							(font
								(size 1.27 1.27)
							)
						)
					)
				)
				(pin passive line
					(at 5.08 0 180)
					(length 2.032)
					(name "~"
						(effects
							(font
								(size 1.27 1.27)
							)
						)
					)
					(number "2"
						(effects
							(font
								(size 1.27 1.27)
							)
						)
					)
				)
			)
		)
	(symbol "thunderbolt-gpu-adapter:C_220n_0402_10"
			(pin_numbers hide)
			(pin_names hide)
			(exclude_from_sim no)
			(in_bom yes)
			(on_board yes)
			(property "Reference" "C"
				(at 20.32 -5.08 0)
				(effects
					(font
						(size 1.27 1.27)
						(thickness 0.15)
					)
					(justify left bottom)
				)
			)
			(property "Value" "C_220n_0402_10"
				(at 20.32 -10.16 0)
				(effects
					(font
						(size 1.27 1.27)
						(thickness 0.15)
					)
					(justify left bottom)
					(hide yes)
				)
			)
			(property "Footprint" "thunderbolt-gpu-adapter-footprints:C_0402_1005Metric"
				(at 20.32 -12.7 0)
				(effects
					(font
						(size 1.27 1.27)
						(thickness 0.15)
					)
					(justify left bottom)
					(hide yes)
				)
			)
			(property "Datasheet" " "
				(at 20.32 -15.24 0)
				(effects
					(font
						(size 1.27 1.27)
						(thickness 0.15)
					)
					(justify left bottom)
					(hide yes)
				)
			)
			(property "Description" " "
				(at 0 0 0)
				(effects
					(font
						(size 1.27 1.27)
					)
					(hide yes)
				)
			)
			(property "MPN" "CC0402KRX5R6BB224"
				(at 20.32 -17.78 0)
				(effects
					(font
						(size 1.27 1.27)
						(thickness 0.15)
					)
					(justify left bottom)
					(hide yes)
				)
			)
			(property "Manufacturer" "Yaego"
				(at 20.32 -20.32 0)
				(effects
					(font
						(size 1.27 1.27)
						(thickness 0.15)
					)
					(justify left bottom)
					(hide yes)
				)
			)
			(property "License" "Apache-2.0"
				(at 20.32 -22.86 0)
				(effects
					(font
						(size 1.27 1.27)
						(thickness 0.15)
					)
					(justify left bottom)
					(hide yes)
				)
			)
			(property "Author" "Antmicro"
				(at 20.32 -25.4 0)
				(effects
					(font
						(size 1.27 1.27)
						(thickness 0.15)
					)
					(justify left bottom)
					(hide yes)
				)
			)
			(property "Val" "220n"
				(at 20.32 -7.62 0)
				(effects
					(font
						(size 1.27 1.27)
						(thickness 0.15)
					)
					(justify left bottom)
				)
			)
			(property "Voltage" ""
				(at 20.32 -27.94 0)
				(effects
					(font
						(size 1.27 1.27)
					)
					(justify left bottom)
					(hide yes)
				)
			)
			(property "Dielectric" ""
				(at 20.32 -30.48 0)
				(effects
					(font
						(size 1.27 1.27)
					)
					(justify left bottom)
					(hide yes)
				)
			)
			(symbol "C_220n_0402_10_0_1"
				(polyline
					(pts
						(xy 2.032 -1.524) (xy 2.032 1.524)
					)
					(stroke
						(width 0.3048)
						(type default)
					)
					(fill
						(type none)
					)
				)
				(polyline
					(pts
						(xy 3.048 -1.524) (xy 3.048 1.524)
					)
					(stroke
						(width 0.3302)
						(type default)
					)
					(fill
						(type none)
					)
				)
			)
			(symbol "C_220n_0402_10_1_1"
				(pin passive line
					(at 0 0 0)
					(length 2.032)
					(name "~"
						(effects
							(font
								(size 1.27 1.27)
							)
						)
					)
					(number "1"
						(effects
							(font
								(size 1.27 1.27)
							)
						)
					)
				)
				(pin passive line
					(at 5.08 0 180)
					(length 2.032)
					(name "~"
						(effects
							(font
								(size 1.27 1.27)
							)
						)
					)
					(number "2"
						(effects
							(font
								(size 1.27 1.27)
							)
						)
					)
				)
			)
		)
	(symbol "thunderbolt-gpu-adapter:C_220n_0402_11"
			(pin_numbers hide)
			(pin_names hide)
			(exclude_from_sim no)
			(in_bom yes)
			(on_board yes)
			(property "Reference" "C"
				(at 20.32 -5.08 0)
				(effects
					(font
						(size 1.27 1.27)
						(thickness 0.15)
					)
					(justify left bottom)
				)
			)
			(property "Value" "C_220n_0402_11"
				(at 20.32 -10.16 0)
				(effects
					(font
						(size 1.27 1.27)
						(thickness 0.15)
					)
					(justify left bottom)
					(hide yes)
				)
			)
			(property "Footprint" "thunderbolt-gpu-adapter-footprints:C_0402_1005Metric"
				(at 20.32 -12.7 0)
				(effects
					(font
						(size 1.27 1.27)
						(thickness 0.15)
					)
					(justify left bottom)
					(hide yes)
				)
			)
			(property "Datasheet" " "
				(at 20.32 -15.24 0)
				(effects
					(font
						(size 1.27 1.27)
						(thickness 0.15)
					)
					(justify left bottom)
					(hide yes)
				)
			)
			(property "Description" " "
				(at 0 0 0)
				(effects
					(font
						(size 1.27 1.27)
					)
					(hide yes)
				)
			)
			(property "MPN" "CC0402KRX5R6BB224"
				(at 20.32 -17.78 0)
				(effects
					(font
						(size 1.27 1.27)
						(thickness 0.15)
					)
					(justify left bottom)
					(hide yes)
				)
			)
			(property "Manufacturer" "Yaego"
				(at 20.32 -20.32 0)
				(effects
					(font
						(size 1.27 1.27)
						(thickness 0.15)
					)
					(justify left bottom)
					(hide yes)
				)
			)
			(property "License" "Apache-2.0"
				(at 20.32 -22.86 0)
				(effects
					(font
						(size 1.27 1.27)
						(thickness 0.15)
					)
					(justify left bottom)
					(hide yes)
				)
			)
			(property "Author" "Antmicro"
				(at 20.32 -25.4 0)
				(effects
					(font
						(size 1.27 1.27)
						(thickness 0.15)
					)
					(justify left bottom)
					(hide yes)
				)
			)
			(property "Val" "220n"
				(at 20.32 -7.62 0)
				(effects
					(font
						(size 1.27 1.27)
						(thickness 0.15)
					)
					(justify left bottom)
				)
			)
			(property "Voltage" ""
				(at 20.32 -27.94 0)
				(effects
					(font
						(size 1.27 1.27)
					)
					(justify left bottom)
					(hide yes)
				)
			)
			(property "Dielectric" ""
				(at 20.32 -30.48 0)
				(effects
					(font
						(size 1.27 1.27)
					)
					(justify left bottom)
					(hide yes)
				)
			)
			(symbol "C_220n_0402_11_0_1"
				(polyline
					(pts
						(xy 2.032 -1.524) (xy 2.032 1.524)
					)
					(stroke
						(width 0.3048)
						(type default)
					)
					(fill
						(type none)
					)
				)
				(polyline
					(pts
						(xy 3.048 -1.524) (xy 3.048 1.524)
					)
					(stroke
						(width 0.3302)
						(type default)
					)
					(fill
						(type none)
					)
				)
			)
			(symbol "C_220n_0402_11_1_1"
				(pin passive line
					(at 0 0 0)
					(length 2.032)
					(name "~"
						(effects
							(font
								(size 1.27 1.27)
							)
						)
					)
					(number "1"
						(effects
							(font
								(size 1.27 1.27)
							)
						)
					)
				)
				(pin passive line
					(at 5.08 0 180)
					(length 2.032)
					(name "~"
						(effects
							(font
								(size 1.27 1.27)
							)
						)
					)
					(number "2"
						(effects
							(font
								(size 1.27 1.27)
							)
						)
					)
				)
			)
		)
	(symbol "thunderbolt-gpu-adapter:R_100k_0402_10"
			(pin_numbers hide)
			(pin_names hide)
			(exclude_from_sim no)
			(in_bom yes)
			(on_board yes)
			(property "Reference" "R"
				(at 20.32 -5.08 0)
				(effects
					(font
						(size 1.27 1.27)
						(thickness 0.15)
					)
					(justify left bottom)
				)
			)
			(property "Value" "R_100k_0402_10"
				(at 20.32 -12.7 0)
				(effects
					(font
						(size 1.27 1.27)
						(thickness 0.15)
					)
					(justify left bottom)
					(hide yes)
				)
			)
			(property "Footprint" "thunderbolt-gpu-adapter-footprints:R_0402_1005Metric"
				(at 20.32 -15.24 0)
				(effects
					(font
						(size 1.27 1.27)
						(thickness 0.15)
					)
					(justify left bottom)
					(hide yes)
				)
			)
			(property "Datasheet" "https://www.bourns.com/docs/product-datasheets/cr.pdf"
				(at 20.32 -17.78 0)
				(effects
					(font
						(size 1.27 1.27)
						(thickness 0.15)
					)
					(justify left bottom)
					(hide yes)
				)
			)
			(property "Description" "100k resistor in 0402 package with 1% tolerance"
				(at 0 0 0)
				(effects
					(font
						(size 1.27 1.27)
					)
					(hide yes)
				)
			)
			(property "MPN" "CR0402-FX-1003GLF"
				(at 20.32 -20.32 0)
				(effects
					(font
						(size 1.27 1.27)
						(thickness 0.15)
					)
					(justify left bottom)
					(hide yes)
				)
			)
			(property "Manufacturer" "Bourns"
				(at 20.32 -22.86 0)
				(effects
					(font
						(size 1.27 1.27)
						(thickness 0.15)
					)
					(justify left bottom)
					(hide yes)
				)
			)
			(property "License" "Apache-2.0"
				(at 20.32 -25.4 0)
				(effects
					(font
						(size 1.27 1.27)
						(thickness 0.15)
					)
					(justify left bottom)
					(hide yes)
				)
			)
			(property "Author" "Antmicro"
				(at 20.32 -27.94 0)
				(effects
					(font
						(size 1.27 1.27)
						(thickness 0.15)
					)
					(justify left bottom)
					(hide yes)
				)
			)
			(property "Val" "100k"
				(at 20.32 -7.62 0)
				(effects
					(font
						(size 1.27 1.27)
						(thickness 0.15)
					)
					(justify left bottom)
				)
			)
			(property "Tolerance" "1%"
				(at 20.32 -10.16 0)
				(effects
					(font
						(size 1.27 1.27)
					)
					(justify left bottom)
					(hide yes)
				)
			)
			(symbol "R_100k_0402_10_0_1"
				(rectangle
					(start 0.635 0.889)
					(end 4.445 -0.889)
					(stroke
						(width 0.254)
						(type default)
					)
					(fill
						(type none)
					)
				)
			)
			(symbol "R_100k_0402_10_1_1"
				(pin passive line
					(at 0 0 0)
					(length 0.635)
					(name "~"
						(effects
							(font
								(size 1.27 1.27)
							)
						)
					)
					(number "1"
						(effects
							(font
								(size 1.27 1.27)
							)
						)
					)
				)
				(pin passive line
					(at 5.08 0 180)
					(length 0.635)
					(name "~"
						(effects
							(font
								(size 1.27 1.27)
							)
						)
					)
					(number "2"
						(effects
							(font
								(size 1.27 1.27)
							)
						)
					)
				)
			)
		)
	(symbol "thunderbolt-gpu-adapter:R_100k_0402_11"
			(pin_numbers hide)
			(pin_names hide)
			(exclude_from_sim no)
			(in_bom yes)
			(on_board yes)
			(property "Reference" "R"
				(at 20.32 -5.08 0)
				(effects
					(font
						(size 1.27 1.27)
						(thickness 0.15)
					)
					(justify left bottom)
				)
			)
			(property "Value" "R_100k_0402_11"
				(at 20.32 -12.7 0)
				(effects
					(font
						(size 1.27 1.27)
						(thickness 0.15)
					)
					(justify left bottom)
					(hide yes)
				)
			)
			(property "Footprint" "thunderbolt-gpu-adapter-footprints:R_0402_1005Metric"
				(at 20.32 -15.24 0)
				(effects
					(font
						(size 1.27 1.27)
						(thickness 0.15)
					)
					(justify left bottom)
					(hide yes)
				)
			)
			(property "Datasheet" "https://www.bourns.com/docs/product-datasheets/cr.pdf"
				(at 20.32 -17.78 0)
				(effects
					(font
						(size 1.27 1.27)
						(thickness 0.15)
					)
					(justify left bottom)
					(hide yes)
				)
			)
			(property "Description" "100k resistor in 0402 package with 1% tolerance"
				(at 0 0 0)
				(effects
					(font
						(size 1.27 1.27)
					)
					(hide yes)
				)
			)
			(property "MPN" "CR0402-FX-1003GLF"
				(at 20.32 -20.32 0)
				(effects
					(font
						(size 1.27 1.27)
						(thickness 0.15)
					)
					(justify left bottom)
					(hide yes)
				)
			)
			(property "Manufacturer" "Bourns"
				(at 20.32 -22.86 0)
				(effects
					(font
						(size 1.27 1.27)
						(thickness 0.15)
					)
					(justify left bottom)
					(hide yes)
				)
			)
			(property "License" "Apache-2.0"
				(at 20.32 -25.4 0)
				(effects
					(font
						(size 1.27 1.27)
						(thickness 0.15)
					)
					(justify left bottom)
					(hide yes)
				)
			)
			(property "Author" "Antmicro"
				(at 20.32 -27.94 0)
				(effects
					(font
						(size 1.27 1.27)
						(thickness 0.15)
					)
					(justify left bottom)
					(hide yes)
				)
			)
			(property "Val" "100k"
				(at 20.32 -7.62 0)
				(effects
					(font
						(size 1.27 1.27)
						(thickness 0.15)
					)
					(justify left bottom)
				)
			)
			(property "Tolerance" "1%"
				(at 20.32 -10.16 0)
				(effects
					(font
						(size 1.27 1.27)
					)
					(justify left bottom)
					(hide yes)
				)
			)
			(symbol "R_100k_0402_11_0_1"
				(rectangle
					(start 0.635 0.889)
					(end 4.445 -0.889)
					(stroke
						(width 0.254)
						(type default)
					)
					(fill
						(type none)
					)
				)
			)
			(symbol "R_100k_0402_11_1_1"
				(pin passive line
					(at 0 0 0)
					(length 0.635)
					(name "~"
						(effects
							(font
								(size 1.27 1.27)
							)
						)
					)
					(number "1"
						(effects
							(font
								(size 1.27 1.27)
							)
						)
					)
				)
				(pin passive line
					(at 5.08 0 180)
					(length 0.635)
					(name "~"
						(effects
							(font
								(size 1.27 1.27)
							)
						)
					)
					(number "2"
						(effects
							(font
								(size 1.27 1.27)
							)
						)
					)
				)
			)
		)
	(symbol "thunderbolt-gpu-adapter:R_100k_0402_12"
			(pin_numbers hide)
			(pin_names hide)
			(exclude_from_sim no)
			(in_bom yes)
			(on_board yes)
			(property "Reference" "R"
				(at 20.32 -5.08 0)
				(effects
					(font
						(size 1.27 1.27)
						(thickness 0.15)
					)
					(justify left bottom)
				)
			)
			(property "Value" "R_100k_0402_12"
				(at 20.32 -12.7 0)
				(effects
					(font
						(size 1.27 1.27)
						(thickness 0.15)
					)
					(justify left bottom)
					(hide yes)
				)
			)
			(property "Footprint" "thunderbolt-gpu-adapter-footprints:R_0402_1005Metric"
				(at 20.32 -15.24 0)
				(effects
					(font
						(size 1.27 1.27)
						(thickness 0.15)
					)
					(justify left bottom)
					(hide yes)
				)
			)
			(property "Datasheet" "https://www.bourns.com/docs/product-datasheets/cr.pdf"
				(at 20.32 -17.78 0)
				(effects
					(font
						(size 1.27 1.27)
						(thickness 0.15)
					)
					(justify left bottom)
					(hide yes)
				)
			)
			(property "Description" "100k resistor in 0402 package with 1% tolerance"
				(at 0 0 0)
				(effects
					(font
						(size 1.27 1.27)
					)
					(hide yes)
				)
			)
			(property "MPN" "CR0402-FX-1003GLF"
				(at 20.32 -20.32 0)
				(effects
					(font
						(size 1.27 1.27)
						(thickness 0.15)
					)
					(justify left bottom)
					(hide yes)
				)
			)
			(property "Manufacturer" "Bourns"
				(at 20.32 -22.86 0)
				(effects
					(font
						(size 1.27 1.27)
						(thickness 0.15)
					)
					(justify left bottom)
					(hide yes)
				)
			)
			(property "License" "Apache-2.0"
				(at 20.32 -25.4 0)
				(effects
					(font
						(size 1.27 1.27)
						(thickness 0.15)
					)
					(justify left bottom)
					(hide yes)
				)
			)
			(property "Author" "Antmicro"
				(at 20.32 -27.94 0)
				(effects
					(font
						(size 1.27 1.27)
						(thickness 0.15)
					)
					(justify left bottom)
					(hide yes)
				)
			)
			(property "Val" "100k"
				(at 20.32 -7.62 0)
				(effects
					(font
						(size 1.27 1.27)
						(thickness 0.15)
					)
					(justify left bottom)
				)
			)
			(property "Tolerance" "1%"
				(at 20.32 -10.16 0)
				(effects
					(font
						(size 1.27 1.27)
					)
					(justify left bottom)
					(hide yes)
				)
			)
			(symbol "R_100k_0402_12_0_1"
				(rectangle
					(start 0.635 0.889)
					(end 4.445 -0.889)
					(stroke
						(width 0.254)
						(type default)
					)
					(fill
						(type none)
					)
				)
			)
			(symbol "R_100k_0402_12_1_1"
				(pin passive line
					(at 0 0 0)
					(length 0.635)
					(name "~"
						(effects
							(font
								(size 1.27 1.27)
							)
						)
					)
					(number "1"
						(effects
							(font
								(size 1.27 1.27)
							)
						)
					)
				)
				(pin passive line
					(at 5.08 0 180)
					(length 0.635)
					(name "~"
						(effects
							(font
								(size 1.27 1.27)
							)
						)
					)
					(number "2"
						(effects
							(font
								(size 1.27 1.27)
							)
						)
					)
				)
			)
		)
	(symbol "thunderbolt-gpu-adapter:R_10k_0402_10"
			(pin_numbers hide)
			(pin_names hide)
			(exclude_from_sim no)
			(in_bom yes)
			(on_board yes)
			(property "Reference" "R"
				(at 20.32 -5.08 0)
				(effects
					(font
						(size 1.27 1.27)
						(thickness 0.15)
					)
					(justify left bottom)
				)
			)
			(property "Value" "R_10k_0402_10"
				(at 20.32 -12.7 0)
				(effects
					(font
						(size 1.27 1.27)
						(thickness 0.15)
					)
					(justify left bottom)
					(hide yes)
				)
			)
			(property "Footprint" "thunderbolt-gpu-adapter-footprints:R_0402_1005Metric"
				(at 20.32 -15.24 0)
				(effects
					(font
						(size 1.27 1.27)
						(thickness 0.15)
					)
					(justify left bottom)
					(hide yes)
				)
			)
			(property "Datasheet" "https://www.bourns.com/docs/product-datasheets/cr.pdf"
				(at 20.32 -17.78 0)
				(effects
					(font
						(size 1.27 1.27)
						(thickness 0.15)
					)
					(justify left bottom)
					(hide yes)
				)
			)
			(property "Description" "10k resistor in 0402 package with 1% tolerance"
				(at 0 0 0)
				(effects
					(font
						(size 1.27 1.27)
					)
					(hide yes)
				)
			)
			(property "MPN" "CR0402-FX-1002GLF"
				(at 20.32 -20.32 0)
				(effects
					(font
						(size 1.27 1.27)
						(thickness 0.15)
					)
					(justify left bottom)
					(hide yes)
				)
			)
			(property "Manufacturer" "Bourns"
				(at 20.32 -22.86 0)
				(effects
					(font
						(size 1.27 1.27)
						(thickness 0.15)
					)
					(justify left bottom)
					(hide yes)
				)
			)
			(property "License" "Apache-2.0"
				(at 20.32 -25.4 0)
				(effects
					(font
						(size 1.27 1.27)
						(thickness 0.15)
					)
					(justify left bottom)
					(hide yes)
				)
			)
			(property "Author" "Antmicro"
				(at 20.32 -27.94 0)
				(effects
					(font
						(size 1.27 1.27)
						(thickness 0.15)
					)
					(justify left bottom)
					(hide yes)
				)
			)
			(property "Val" "10k"
				(at 20.32 -7.62 0)
				(effects
					(font
						(size 1.27 1.27)
						(thickness 0.15)
					)
					(justify left bottom)
				)
			)
			(property "Tolerance" "1%"
				(at 20.32 -10.16 0)
				(effects
					(font
						(size 1.27 1.27)
					)
					(justify left bottom)
					(hide yes)
				)
			)
			(symbol "R_10k_0402_10_0_1"
				(rectangle
					(start 0.635 0.889)
					(end 4.445 -0.889)
					(stroke
						(width 0.254)
						(type default)
					)
					(fill
						(type none)
					)
				)
			)
			(symbol "R_10k_0402_10_1_1"
				(pin passive line
					(at 0 0 0)
					(length 0.635)
					(name "~"
						(effects
							(font
								(size 1.27 1.27)
							)
						)
					)
					(number "1"
						(effects
							(font
								(size 1.27 1.27)
							)
						)
					)
				)
				(pin passive line
					(at 5.08 0 180)
					(length 0.635)
					(name "~"
						(effects
							(font
								(size 1.27 1.27)
							)
						)
					)
					(number "2"
						(effects
							(font
								(size 1.27 1.27)
							)
						)
					)
				)
			)
		)
	(symbol "thunderbolt-gpu-adapter:R_10k_0402_11"
			(pin_numbers hide)
			(pin_names hide)
			(exclude_from_sim no)
			(in_bom yes)
			(on_board yes)
			(property "Reference" "R"
				(at 20.32 -5.08 0)
				(effects
					(font
						(size 1.27 1.27)
						(thickness 0.15)
					)
					(justify left bottom)
				)
			)
			(property "Value" "R_10k_0402_11"
				(at 20.32 -12.7 0)
				(effects
					(font
						(size 1.27 1.27)
						(thickness 0.15)
					)
					(justify left bottom)
					(hide yes)
				)
			)
			(property "Footprint" "thunderbolt-gpu-adapter-footprints:R_0402_1005Metric"
				(at 20.32 -15.24 0)
				(effects
					(font
						(size 1.27 1.27)
						(thickness 0.15)
					)
					(justify left bottom)
					(hide yes)
				)
			)
			(property "Datasheet" "https://www.bourns.com/docs/product-datasheets/cr.pdf"
				(at 20.32 -17.78 0)
				(effects
					(font
						(size 1.27 1.27)
						(thickness 0.15)
					)
					(justify left bottom)
					(hide yes)
				)
			)
			(property "Description" "10k resistor in 0402 package with 1% tolerance"
				(at 0 0 0)
				(effects
					(font
						(size 1.27 1.27)
					)
					(hide yes)
				)
			)
			(property "MPN" "CR0402-FX-1002GLF"
				(at 20.32 -20.32 0)
				(effects
					(font
						(size 1.27 1.27)
						(thickness 0.15)
					)
					(justify left bottom)
					(hide yes)
				)
			)
			(property "Manufacturer" "Bourns"
				(at 20.32 -22.86 0)
				(effects
					(font
						(size 1.27 1.27)
						(thickness 0.15)
					)
					(justify left bottom)
					(hide yes)
				)
			)
			(property "License" "Apache-2.0"
				(at 20.32 -25.4 0)
				(effects
					(font
						(size 1.27 1.27)
						(thickness 0.15)
					)
					(justify left bottom)
					(hide yes)
				)
			)
			(property "Author" "Antmicro"
				(at 20.32 -27.94 0)
				(effects
					(font
						(size 1.27 1.27)
						(thickness 0.15)
					)
					(justify left bottom)
					(hide yes)
				)
			)
			(property "Val" "10k"
				(at 20.32 -7.62 0)
				(effects
					(font
						(size 1.27 1.27)
						(thickness 0.15)
					)
					(justify left bottom)
				)
			)
			(property "Tolerance" "1%"
				(at 20.32 -10.16 0)
				(effects
					(font
						(size 1.27 1.27)
					)
					(justify left bottom)
					(hide yes)
				)
			)
			(symbol "R_10k_0402_11_0_1"
				(rectangle
					(start 0.635 0.889)
					(end 4.445 -0.889)
					(stroke
						(width 0.254)
						(type default)
					)
					(fill
						(type none)
					)
				)
			)
			(symbol "R_10k_0402_11_1_1"
				(pin passive line
					(at 0 0 0)
					(length 0.635)
					(name "~"
						(effects
							(font
								(size 1.27 1.27)
							)
						)
					)
					(number "1"
						(effects
							(font
								(size 1.27 1.27)
							)
						)
					)
				)
				(pin passive line
					(at 5.08 0 180)
					(length 0.635)
					(name "~"
						(effects
							(font
								(size 1.27 1.27)
							)
						)
					)
					(number "2"
						(effects
							(font
								(size 1.27 1.27)
							)
						)
					)
				)
			)
		)
	(symbol "thunderbolt-gpu-adapter:R_10k_0402_12"
			(pin_numbers hide)
			(pin_names hide)
			(exclude_from_sim no)
			(in_bom yes)
			(on_board yes)
			(property "Reference" "R"
				(at 20.32 -5.08 0)
				(effects
					(font
						(size 1.27 1.27)
						(thickness 0.15)
					)
					(justify left bottom)
				)
			)
			(property "Value" "R_10k_0402_12"
				(at 20.32 -12.7 0)
				(effects
					(font
						(size 1.27 1.27)
						(thickness 0.15)
					)
					(justify left bottom)
					(hide yes)
				)
			)
			(property "Footprint" "thunderbolt-gpu-adapter-footprints:R_0402_1005Metric"
				(at 20.32 -15.24 0)
				(effects
					(font
						(size 1.27 1.27)
						(thickness 0.15)
					)
					(justify left bottom)
					(hide yes)
				)
			)
			(property "Datasheet" "https://www.bourns.com/docs/product-datasheets/cr.pdf"
				(at 20.32 -17.78 0)
				(effects
					(font
						(size 1.27 1.27)
						(thickness 0.15)
					)
					(justify left bottom)
					(hide yes)
				)
			)
			(property "Description" "10k resistor in 0402 package with 1% tolerance"
				(at 0 0 0)
				(effects
					(font
						(size 1.27 1.27)
					)
					(hide yes)
				)
			)
			(property "MPN" "CR0402-FX-1002GLF"
				(at 20.32 -20.32 0)
				(effects
					(font
						(size 1.27 1.27)
						(thickness 0.15)
					)
					(justify left bottom)
					(hide yes)
				)
			)
			(property "Manufacturer" "Bourns"
				(at 20.32 -22.86 0)
				(effects
					(font
						(size 1.27 1.27)
						(thickness 0.15)
					)
					(justify left bottom)
					(hide yes)
				)
			)
			(property "License" "Apache-2.0"
				(at 20.32 -25.4 0)
				(effects
					(font
						(size 1.27 1.27)
						(thickness 0.15)
					)
					(justify left bottom)
					(hide yes)
				)
			)
			(property "Author" "Antmicro"
				(at 20.32 -27.94 0)
				(effects
					(font
						(size 1.27 1.27)
						(thickness 0.15)
					)
					(justify left bottom)
					(hide yes)
				)
			)
			(property "Val" "10k"
				(at 20.32 -7.62 0)
				(effects
					(font
						(size 1.27 1.27)
						(thickness 0.15)
					)
					(justify left bottom)
				)
			)
			(property "Tolerance" "1%"
				(at 20.32 -10.16 0)
				(effects
					(font
						(size 1.27 1.27)
					)
					(justify left bottom)
					(hide yes)
				)
			)
			(symbol "R_10k_0402_12_0_1"
				(rectangle
					(start 0.635 0.889)
					(end 4.445 -0.889)
					(stroke
						(width 0.254)
						(type default)
					)
					(fill
						(type none)
					)
				)
			)
			(symbol "R_10k_0402_12_1_1"
				(pin passive line
					(at 0 0 0)
					(length 0.635)
					(name "~"
						(effects
							(font
								(size 1.27 1.27)
							)
						)
					)
					(number "1"
						(effects
							(font
								(size 1.27 1.27)
							)
						)
					)
				)
				(pin passive line
					(at 5.08 0 180)
					(length 0.635)
					(name "~"
						(effects
							(font
								(size 1.27 1.27)
							)
						)
					)
					(number "2"
						(effects
							(font
								(size 1.27 1.27)
							)
						)
					)
				)
			)
		)
	(symbol "thunderbolt-gpu-adapter:R_10k_0402_13"
			(pin_numbers hide)
			(pin_names hide)
			(exclude_from_sim no)
			(in_bom yes)
			(on_board yes)
			(property "Reference" "R"
				(at 20.32 -5.08 0)
				(effects
					(font
						(size 1.27 1.27)
						(thickness 0.15)
					)
					(justify left bottom)
				)
			)
			(property "Value" "R_10k_0402_13"
				(at 20.32 -12.7 0)
				(effects
					(font
						(size 1.27 1.27)
						(thickness 0.15)
					)
					(justify left bottom)
					(hide yes)
				)
			)
			(property "Footprint" "thunderbolt-gpu-adapter-footprints:R_0402_1005Metric"
				(at 20.32 -15.24 0)
				(effects
					(font
						(size 1.27 1.27)
						(thickness 0.15)
					)
					(justify left bottom)
					(hide yes)
				)
			)
			(property "Datasheet" "https://www.bourns.com/docs/product-datasheets/cr.pdf"
				(at 20.32 -17.78 0)
				(effects
					(font
						(size 1.27 1.27)
						(thickness 0.15)
					)
					(justify left bottom)
					(hide yes)
				)
			)
			(property "Description" "10k resistor in 0402 package with 1% tolerance"
				(at 0 0 0)
				(effects
					(font
						(size 1.27 1.27)
					)
					(hide yes)
				)
			)
			(property "MPN" "CR0402-FX-1002GLF"
				(at 20.32 -20.32 0)
				(effects
					(font
						(size 1.27 1.27)
						(thickness 0.15)
					)
					(justify left bottom)
					(hide yes)
				)
			)
			(property "Manufacturer" "Bourns"
				(at 20.32 -22.86 0)
				(effects
					(font
						(size 1.27 1.27)
						(thickness 0.15)
					)
					(justify left bottom)
					(hide yes)
				)
			)
			(property "License" "Apache-2.0"
				(at 20.32 -25.4 0)
				(effects
					(font
						(size 1.27 1.27)
						(thickness 0.15)
					)
					(justify left bottom)
					(hide yes)
				)
			)
			(property "Author" "Antmicro"
				(at 20.32 -27.94 0)
				(effects
					(font
						(size 1.27 1.27)
						(thickness 0.15)
					)
					(justify left bottom)
					(hide yes)
				)
			)
			(property "Val" "10k"
				(at 20.32 -7.62 0)
				(effects
					(font
						(size 1.27 1.27)
						(thickness 0.15)
					)
					(justify left bottom)
				)
			)
			(property "Tolerance" "1%"
				(at 20.32 -10.16 0)
				(effects
					(font
						(size 1.27 1.27)
					)
					(justify left bottom)
					(hide yes)
				)
			)
			(symbol "R_10k_0402_13_0_1"
				(rectangle
					(start 0.635 0.889)
					(end 4.445 -0.889)
					(stroke
						(width 0.254)
						(type default)
					)
					(fill
						(type none)
					)
				)
			)
			(symbol "R_10k_0402_13_1_1"
				(pin passive line
					(at 0 0 0)
					(length 0.635)
					(name "~"
						(effects
							(font
								(size 1.27 1.27)
							)
						)
					)
					(number "1"
						(effects
							(font
								(size 1.27 1.27)
							)
						)
					)
				)
				(pin passive line
					(at 5.08 0 180)
					(length 0.635)
					(name "~"
						(effects
							(font
								(size 1.27 1.27)
							)
						)
					)
					(number "2"
						(effects
							(font
								(size 1.27 1.27)
							)
						)
					)
				)
			)
		)
)
